FILE_TYPE = MACRO_DRAWING;
SET COLOR_WIRE YELLOW;
SET COLOR_PROP MONO;
SET COLOR_DOT WHITE;
SET COLOR_ARC YELLOW;
SET COLOR_BODY GREEN;
SET COLOR_NOTE MONO;
SET PROP_DISPLAY VALUE;
SET PAGE_NUMBER P195;
FORCEADD CAPP..1
(-7700 775);
FORCEPROP 1 LASTPIN (-7700 875) $PN 1
J 0
(-7690 860);
DISPLAY 0.787234 (-7690 860);
PAINT ORANGE (-7690 860);
FORCEPROP 1 LASTPIN (-7700 675) $PN 2
J 0
(-7690 660);
DISPLAY 0.787234 (-7690 660);
PAINT ORANGE (-7690 660);
FORCEPROP 1 LAST PACK_TYPE 3018
J 0
(-7650 625);
DISPLAY 0.617021 (-7650 625);
PAINT SKYBLUE (-7650 625);
FORCEPROP 1 LAST MATERIAL TANT
J 0
(-7650 675);
DISPLAY 0.617021 (-7650 675);
PAINT SKYBLUE (-7650 675);
FORCEPROP 1 LAST PART_NUMBER 724613-112
J 0
(-7650 575);
DISPLAY 0.617021 (-7650 575);
PAINT BLUE (-7650 575);
FORCEPROP 1 LAST VOLTAGE 16V
J 0
(-7650 725);
DISPLAY 0.617021 (-7650 725);
PAINT SKYBLUE (-7650 725);
FORCEPROP 1 LAST TOLERANCE 20%
J 0
(-7650 775);
DISPLAY 0.617021 (-7650 775);
PAINT SKYBLUE (-7650 775);
FORCEPROP 1 LAST VALUE 68UF
J 0
(-7650 825);
DISPLAY 0.617021 (-7650 825);
PAINT SKYBLUE (-7650 825);
FORCEPROP 1 LAST LOCATION C3B6
J 0
(-7650 875);
DISPLAY 0.617021 (-7650 875);
PAINT AQUA (-7650 875);
FORCEPROP 2 LAST SEC_TYPE 3018
J 0
(-7650 975);
DISPLAY 1.021277 (-7650 975);
PAINT ORANGE (-7650 975);
DISPLAY INVISIBLE (-7650 975);
FORCEPROP 2 LAST SEC 1
J 0
(-7650 975);
PAINT MONO (-7650 975);
DISPLAY INVISIBLE (-7650 975);
FORCEPROP 2 LAST CDS_LIB mstr_discrete
J 0
(-7700 775);
PAINT MONO (-7700 775);
DISPLAY INVISIBLE (-7700 775);
FORCEPROP 1 LAST PATH I100
J 0
(-7650 925);
DISPLAY 0.978723 (-7650 925);
PAINT ORANGE (-7650 925);
DISPLAY INVISIBLE (-7650 925);
FORCEPROP 2 LAST CDS_LOCATION C3B6
J 0
(-7650 875);
DISPLAY 0.617021 (-7650 875);
PAINT AQUA (-7650 875);
DISPLAY INVISIBLE (-7650 875);
FORCEADD CAPP..1
(-6175 775);
FORCEPROP 1 LAST PART_NUMBER 724613-112
J 0
(-6125 575);
DISPLAY 0.617021 (-6125 575);
PAINT BLUE (-6125 575);
FORCEPROP 1 LASTPIN (-6175 875) $PN 1
J 0
(-6165 860);
DISPLAY 0.787234 (-6165 860);
PAINT ORANGE (-6165 860);
FORCEPROP 1 LASTPIN (-6175 675) $PN 2
J 0
(-6165 660);
DISPLAY 0.787234 (-6165 660);
PAINT ORANGE (-6165 660);
FORCEPROP 1 LAST PACK_TYPE 3018
J 0
(-6125 625);
DISPLAY 0.617021 (-6125 625);
PAINT SKYBLUE (-6125 625);
FORCEPROP 1 LAST MATERIAL TANT
J 0
(-6125 675);
DISPLAY 0.617021 (-6125 675);
PAINT SKYBLUE (-6125 675);
FORCEPROP 1 LAST VOLTAGE 16V
J 0
(-6125 725);
DISPLAY 0.617021 (-6125 725);
PAINT SKYBLUE (-6125 725);
FORCEPROP 1 LAST TOLERANCE 20%
J 0
(-6125 775);
DISPLAY 0.617021 (-6125 775);
PAINT SKYBLUE (-6125 775);
FORCEPROP 1 LAST VALUE 68UF
J 0
(-6125 825);
DISPLAY 0.617021 (-6125 825);
PAINT SKYBLUE (-6125 825);
FORCEPROP 1 LAST LOCATION C1R23
J 0
(-6125 875);
DISPLAY 0.617021 (-6125 875);
PAINT AQUA (-6125 875);
FORCEPROP 2 LAST SEC_TYPE 3018
J 0
(-6125 975);
DISPLAY 1.021277 (-6125 975);
PAINT ORANGE (-6125 975);
DISPLAY INVISIBLE (-6125 975);
FORCEPROP 2 LAST SEC 1
J 0
(-6125 975);
PAINT MONO (-6125 975);
DISPLAY INVISIBLE (-6125 975);
FORCEPROP 2 LAST CDS_LIB mstr_discrete
J 0
(-6175 775);
PAINT MONO (-6175 775);
DISPLAY INVISIBLE (-6175 775);
FORCEPROP 1 LAST PATH I101
J 0
(-6125 925);
DISPLAY 0.978723 (-6125 925);
PAINT ORANGE (-6125 925);
DISPLAY INVISIBLE (-6125 925);
FORCEPROP 2 LAST CDS_LOCATION C1R23
J 0
(-6125 875);
DISPLAY 0.617021 (-6125 875);
PAINT AQUA (-6125 875);
DISPLAY INVISIBLE (-6125 875);
FORCEADD CAPP..1
(-4875 775);
FORCEPROP 1 LAST VOLTAGE 16V
J 0
(-4825 725);
DISPLAY 0.617021 (-4825 725);
PAINT SKYBLUE (-4825 725);
FORCEPROP 1 LASTPIN (-4875 875) $PN 1
J 0
(-4865 860);
DISPLAY 0.787234 (-4865 860);
PAINT ORANGE (-4865 860);
FORCEPROP 1 LASTPIN (-4875 675) $PN 2
J 0
(-4865 660);
DISPLAY 0.787234 (-4865 660);
PAINT ORANGE (-4865 660);
FORCEPROP 1 LAST PACK_TYPE 3018
J 0
(-4825 625);
DISPLAY 0.617021 (-4825 625);
PAINT SKYBLUE (-4825 625);
FORCEPROP 1 LAST MATERIAL TANT
J 0
(-4825 675);
DISPLAY 0.617021 (-4825 675);
PAINT SKYBLUE (-4825 675);
FORCEPROP 1 LAST TOLERANCE 20%
J 0
(-4825 775);
DISPLAY 0.617021 (-4825 775);
PAINT SKYBLUE (-4825 775);
FORCEPROP 1 LAST VALUE 68UF
J 0
(-4825 825);
DISPLAY 0.617021 (-4825 825);
PAINT SKYBLUE (-4825 825);
FORCEPROP 1 LAST LOCATION C4M6
J 0
(-4825 875);
DISPLAY 0.617021 (-4825 875);
PAINT AQUA (-4825 875);
FORCEPROP 1 LAST PART_NUMBER 724613-112
J 0
(-4825 575);
DISPLAY 0.617021 (-4825 575);
PAINT BLUE (-4825 575);
FORCEPROP 2 LAST SEC_TYPE 3018
J 0
(-4825 975);
DISPLAY 1.021277 (-4825 975);
PAINT ORANGE (-4825 975);
DISPLAY INVISIBLE (-4825 975);
FORCEPROP 2 LAST SEC 1
J 0
(-4825 975);
PAINT MONO (-4825 975);
DISPLAY INVISIBLE (-4825 975);
FORCEPROP 2 LAST CDS_LIB mstr_discrete
J 0
(-4875 775);
PAINT MONO (-4875 775);
DISPLAY INVISIBLE (-4875 775);
FORCEPROP 1 LAST PATH I102
J 0
(-4825 925);
DISPLAY 0.978723 (-4825 925);
PAINT ORANGE (-4825 925);
DISPLAY INVISIBLE (-4825 925);
FORCEPROP 2 LAST CDS_LOCATION C4M6
J 0
(-4825 875);
DISPLAY 0.617021 (-4825 875);
PAINT AQUA (-4825 875);
DISPLAY INVISIBLE (-4825 875);
FORCEADD CAPP..1
(-6550 775);
FORCEPROP 1 LASTPIN (-6550 875) $PN 1
J 0
(-6540 860);
DISPLAY 0.787234 (-6540 860);
PAINT ORANGE (-6540 860);
FORCEPROP 1 LASTPIN (-6550 675) $PN 2
J 0
(-6540 660);
DISPLAY 0.787234 (-6540 660);
PAINT ORANGE (-6540 660);
FORCEPROP 1 LAST PACK_TYPE 3018
J 0
(-6500 625);
DISPLAY 0.617021 (-6500 625);
PAINT SKYBLUE (-6500 625);
FORCEPROP 1 LAST MATERIAL TANT
J 0
(-6500 675);
DISPLAY 0.617021 (-6500 675);
PAINT SKYBLUE (-6500 675);
FORCEPROP 1 LAST PART_NUMBER 724613-112
J 0
(-6500 575);
DISPLAY 0.617021 (-6500 575);
PAINT BLUE (-6500 575);
FORCEPROP 1 LAST VOLTAGE 16V
J 0
(-6500 725);
DISPLAY 0.617021 (-6500 725);
PAINT SKYBLUE (-6500 725);
FORCEPROP 1 LAST TOLERANCE 20%
J 0
(-6500 775);
DISPLAY 0.617021 (-6500 775);
PAINT SKYBLUE (-6500 775);
FORCEPROP 1 LAST VALUE 68UF
J 0
(-6500 825);
DISPLAY 0.617021 (-6500 825);
PAINT SKYBLUE (-6500 825);
FORCEPROP 1 LAST LOCATION C1M5
J 0
(-6500 875);
DISPLAY 0.617021 (-6500 875);
PAINT AQUA (-6500 875);
FORCEPROP 2 LAST SEC_TYPE 3018
J 0
(-6500 975);
DISPLAY 1.021277 (-6500 975);
PAINT ORANGE (-6500 975);
DISPLAY INVISIBLE (-6500 975);
FORCEPROP 2 LAST SEC 1
J 0
(-6500 975);
PAINT MONO (-6500 975);
DISPLAY INVISIBLE (-6500 975);
FORCEPROP 2 LAST CDS_LIB mstr_discrete
J 0
(-6550 775);
PAINT MONO (-6550 775);
DISPLAY INVISIBLE (-6550 775);
FORCEPROP 2 LAST CDS_LOCATION C1M5
J 0
(-6500 875);
DISPLAY 0.617021 (-6500 875);
PAINT AQUA (-6500 875);
DISPLAY INVISIBLE (-6500 875);
FORCEPROP 1 LAST PATH I103
J 0
(-6500 925);
DISPLAY 0.978723 (-6500 925);
PAINT ORANGE (-6500 925);
DISPLAY INVISIBLE (-6500 925);
FORCEADD CAPP..1
(-5725 1950);
FORCEPROP 1 LAST VALUE 68UF
J 0
(-5675 2000);
DISPLAY 0.617021 (-5675 2000);
PAINT SKYBLUE (-5675 2000);
FORCEPROP 1 LAST LOCATION C3T13
J 0
(-5675 2050);
DISPLAY 0.617021 (-5675 2050);
PAINT AQUA (-5675 2050);
FORCEPROP 1 LASTPIN (-5725 2050) $PN 1
J 0
(-5715 2035);
DISPLAY 0.787234 (-5715 2035);
PAINT ORANGE (-5715 2035);
FORCEPROP 1 LASTPIN (-5725 1850) $PN 2
J 0
(-5715 1835);
DISPLAY 0.787234 (-5715 1835);
PAINT ORANGE (-5715 1835);
FORCEPROP 1 LAST PACK_TYPE 3018
J 0
(-5675 1800);
DISPLAY 0.617021 (-5675 1800);
PAINT SKYBLUE (-5675 1800);
FORCEPROP 1 LAST PART_NUMBER 724613-112
J 0
(-5675 1750);
DISPLAY 0.617021 (-5675 1750);
PAINT BLUE (-5675 1750);
FORCEPROP 1 LAST MATERIAL TANT
J 0
(-5675 1850);
DISPLAY 0.617021 (-5675 1850);
PAINT SKYBLUE (-5675 1850);
FORCEPROP 1 LAST VOLTAGE 16V
J 0
(-5675 1900);
DISPLAY 0.617021 (-5675 1900);
PAINT SKYBLUE (-5675 1900);
FORCEPROP 1 LAST TOLERANCE 20%
J 0
(-5675 1950);
DISPLAY 0.617021 (-5675 1950);
PAINT SKYBLUE (-5675 1950);
FORCEPROP 2 LAST SEC_TYPE 3018
J 0
(-5675 2150);
DISPLAY 1.021277 (-5675 2150);
PAINT ORANGE (-5675 2150);
DISPLAY INVISIBLE (-5675 2150);
FORCEPROP 2 LAST SEC 1
J 0
(-5675 2150);
PAINT MONO (-5675 2150);
DISPLAY INVISIBLE (-5675 2150);
FORCEPROP 2 LAST CDS_LIB mstr_discrete
J 0
(-5725 1950);
PAINT MONO (-5725 1950);
DISPLAY INVISIBLE (-5725 1950);
FORCEPROP 2 LAST CDS_LOCATION C3T13
J 0
(-5675 2050);
DISPLAY 0.617021 (-5675 2050);
PAINT AQUA (-5675 2050);
DISPLAY INVISIBLE (-5675 2050);
FORCEPROP 1 LAST PATH I104
J 0
(-5675 2100);
DISPLAY 0.978723 (-5675 2100);
PAINT ORANGE (-5675 2100);
DISPLAY INVISIBLE (-5675 2100);
FORCEADD CAPP..1
(-4850 1950);
FORCEPROP 1 LASTPIN (-4850 2050) $PN 1
J 0
(-4840 2035);
DISPLAY 0.787234 (-4840 2035);
PAINT ORANGE (-4840 2035);
FORCEPROP 1 LASTPIN (-4850 1850) $PN 2
J 0
(-4840 1835);
DISPLAY 0.787234 (-4840 1835);
PAINT ORANGE (-4840 1835);
FORCEPROP 1 LAST PACK_TYPE 3018
J 0
(-4800 1800);
DISPLAY 0.617021 (-4800 1800);
PAINT SKYBLUE (-4800 1800);
FORCEPROP 1 LAST VOLTAGE 16V
J 0
(-4800 1900);
DISPLAY 0.617021 (-4800 1900);
PAINT SKYBLUE (-4800 1900);
FORCEPROP 1 LAST MATERIAL TANT
J 0
(-4800 1850);
DISPLAY 0.617021 (-4800 1850);
PAINT SKYBLUE (-4800 1850);
FORCEPROP 1 LAST PART_NUMBER 724613-112
J 0
(-4800 1750);
DISPLAY 0.617021 (-4800 1750);
PAINT BLUE (-4800 1750);
FORCEPROP 1 LAST VALUE 68UF
J 0
(-4800 2000);
DISPLAY 0.617021 (-4800 2000);
PAINT SKYBLUE (-4800 2000);
FORCEPROP 1 LAST TOLERANCE 20%
J 0
(-4800 1950);
DISPLAY 0.617021 (-4800 1950);
PAINT SKYBLUE (-4800 1950);
FORCEPROP 1 LAST LOCATION C4M7
J 0
(-4800 2050);
DISPLAY 0.617021 (-4800 2050);
PAINT AQUA (-4800 2050);
FORCEPROP 2 LAST SEC_TYPE 3018
J 0
(-4800 2150);
DISPLAY 1.021277 (-4800 2150);
PAINT ORANGE (-4800 2150);
DISPLAY INVISIBLE (-4800 2150);
FORCEPROP 2 LAST SEC 1
J 0
(-4800 2150);
PAINT MONO (-4800 2150);
DISPLAY INVISIBLE (-4800 2150);
FORCEPROP 2 LAST CDS_LIB mstr_discrete
J 0
(-4850 1950);
PAINT MONO (-4850 1950);
DISPLAY INVISIBLE (-4850 1950);
FORCEPROP 1 LAST PATH I105
J 0
(-4800 2100);
DISPLAY 0.978723 (-4800 2100);
PAINT ORANGE (-4800 2100);
DISPLAY INVISIBLE (-4800 2100);
FORCEPROP 2 LAST CDS_LOCATION C4M7
J 0
(-4800 2050);
DISPLAY 0.617021 (-4800 2050);
PAINT AQUA (-4800 2050);
DISPLAY INVISIBLE (-4800 2050);
FORCEADD CAPP..1
(-5275 1925);
FORCEPROP 1 LASTPIN (-5275 2025) $PN 1
J 0
(-5265 2010);
DISPLAY 0.787234 (-5265 2010);
PAINT ORANGE (-5265 2010);
FORCEPROP 1 LASTPIN (-5275 1825) $PN 2
J 0
(-5265 1810);
DISPLAY 0.787234 (-5265 1810);
PAINT ORANGE (-5265 1810);
FORCEPROP 1 LAST PACK_TYPE 3018
J 0
(-5225 1775);
DISPLAY 0.617021 (-5225 1775);
PAINT SKYBLUE (-5225 1775);
FORCEPROP 1 LAST LOCATION C3T15
J 0
(-5225 2025);
DISPLAY 0.617021 (-5225 2025);
PAINT AQUA (-5225 2025);
FORCEPROP 1 LAST PART_NUMBER 724613-112
J 0
(-5225 1725);
DISPLAY 0.617021 (-5225 1725);
PAINT BLUE (-5225 1725);
FORCEPROP 1 LAST VALUE 68UF
J 0
(-5225 1975);
DISPLAY 0.617021 (-5225 1975);
PAINT SKYBLUE (-5225 1975);
FORCEPROP 1 LAST MATERIAL TANT
J 0
(-5225 1825);
DISPLAY 0.617021 (-5225 1825);
PAINT SKYBLUE (-5225 1825);
FORCEPROP 1 LAST TOLERANCE 20%
J 0
(-5225 1925);
DISPLAY 0.617021 (-5225 1925);
PAINT SKYBLUE (-5225 1925);
FORCEPROP 1 LAST VOLTAGE 16V
J 0
(-5225 1875);
DISPLAY 0.617021 (-5225 1875);
PAINT SKYBLUE (-5225 1875);
FORCEPROP 2 LAST SEC_TYPE 3018
J 0
(-5225 2125);
DISPLAY 1.021277 (-5225 2125);
PAINT ORANGE (-5225 2125);
DISPLAY INVISIBLE (-5225 2125);
FORCEPROP 2 LAST SEC 1
J 0
(-5225 2125);
PAINT MONO (-5225 2125);
DISPLAY INVISIBLE (-5225 2125);
FORCEPROP 1 LAST PATH I106
J 0
(-5225 2075);
DISPLAY 0.978723 (-5225 2075);
PAINT ORANGE (-5225 2075);
DISPLAY INVISIBLE (-5225 2075);
FORCEPROP 2 LAST CDS_LOCATION C3T15
J 0
(-5225 2025);
DISPLAY 0.617021 (-5225 2025);
PAINT AQUA (-5225 2025);
DISPLAY INVISIBLE (-5225 2025);
FORCEPROP 2 LAST CDS_LIB mstr_discrete
J 0
(-5275 1925);
PAINT MONO (-5275 1925);
DISPLAY INVISIBLE (-5275 1925);
FORCEADD P12V_STBY..1
(-6375 2325);
FORCEPROP 3 LASTPIN (-6375 2275) SIG_NAME P12V_STBY\g
J 0
(-6365 2285);
DISPLAY 0.659574 (-6365 2285);
PAINT MONO (-6365 2285);
DISPLAY INVISIBLE (-6365 2285);
FORCEPROP 1 LAST VOLTAGE 12.0V
J 0
(-6420 2282);
DISPLAY 0.340426 (-6420 2282);
PAINT SKYBLUE (-6420 2282);
DISPLAY INVISIBLE (-6420 2282);
FORCEPROP 1 LAST SIZE 1B
J 0
(-6330 2347);
DISPLAY 0.340426 (-6330 2347);
PAINT GREEN (-6330 2347);
DISPLAY INVISIBLE (-6330 2347);
FORCEPROP 2 LAST CDS_LIB mstr_symbols
J 0
(-6375 2325);
PAINT MONO (-6375 2325);
DISPLAY INVISIBLE (-6375 2325);
FORCEPROP 1 LAST PATH I107
J 0
(-6330 2327);
DISPLAY 0.340426 (-6330 2327);
PAINT GREEN (-6330 2327);
DISPLAY INVISIBLE (-6330 2327);
FORCEPROP 1 LAST BODY_TYPE PLUMBING
J 0
(-6420 2282);
DISPLAY 0.340426 (-6420 2282);
PAINT GREEN (-6420 2282);
DISPLAY INVISIBLE (-6420 2282);
FORCEPROP 1 LAST HDL_POWER P12V_STBY
J 0
(-6675 2200);
DISPLAY 0.872340 (-6675 2200);
PAINT ORANGE (-6675 2200);
DISPLAY INVISIBLE (-6675 2200);
FORCEADD CAPP..1
(-6150 1950);
FORCEPROP 1 LASTPIN (-6150 1850) $PN 2
J 0
(-6140 1835);
DISPLAY 0.787234 (-6140 1835);
PAINT ORANGE (-6140 1835);
FORCEPROP 1 LAST MATERIAL TANT
J 0
(-6100 1850);
DISPLAY 0.617021 (-6100 1850);
PAINT SKYBLUE (-6100 1850);
FORCEPROP 1 LAST VOLTAGE 16V
J 0
(-6100 1900);
DISPLAY 0.617021 (-6100 1900);
PAINT SKYBLUE (-6100 1900);
FORCEPROP 1 LASTPIN (-6150 2050) $PN 1
J 0
(-6140 2035);
DISPLAY 0.787234 (-6140 2035);
PAINT ORANGE (-6140 2035);
FORCEPROP 1 LAST PACK_TYPE 3018
J 0
(-6100 1800);
DISPLAY 0.617021 (-6100 1800);
PAINT SKYBLUE (-6100 1800);
FORCEPROP 1 LAST TOLERANCE 20%
J 0
(-6100 1950);
DISPLAY 0.617021 (-6100 1950);
PAINT SKYBLUE (-6100 1950);
FORCEPROP 1 LAST PART_NUMBER 724613-112
J 0
(-6100 1750);
DISPLAY 0.617021 (-6100 1750);
PAINT BLUE (-6100 1750);
FORCEPROP 1 LAST VALUE 68UF
J 0
(-6100 2000);
DISPLAY 0.617021 (-6100 2000);
PAINT SKYBLUE (-6100 2000);
FORCEPROP 1 LAST LOCATION C7M6
J 0
(-6100 2050);
DISPLAY 0.617021 (-6100 2050);
PAINT AQUA (-6100 2050);
FORCEPROP 2 LAST SEC_TYPE 3018
J 0
(-6100 2150);
DISPLAY 1.021277 (-6100 2150);
PAINT ORANGE (-6100 2150);
DISPLAY INVISIBLE (-6100 2150);
FORCEPROP 2 LAST SEC 1
J 0
(-6100 2150);
PAINT MONO (-6100 2150);
DISPLAY INVISIBLE (-6100 2150);
FORCEPROP 2 LAST CDS_LIB mstr_discrete
J 0
(-6150 1950);
PAINT MONO (-6150 1950);
DISPLAY INVISIBLE (-6150 1950);
FORCEPROP 2 LAST CDS_LOCATION C7M6
J 0
(-6100 2050);
DISPLAY 0.617021 (-6100 2050);
PAINT AQUA (-6100 2050);
DISPLAY INVISIBLE (-6100 2050);
FORCEPROP 1 LAST PATH I108
J 0
(-6100 2100);
DISPLAY 0.978723 (-6100 2100);
PAINT ORANGE (-6100 2100);
DISPLAY INVISIBLE (-6100 2100);
FORCEADD CAPP..1
(-6525 1950);
FORCEPROP 1 LAST PART_NUMBER 724613-112
J 0
(-6475 1750);
DISPLAY 0.617021 (-6475 1750);
PAINT BLUE (-6475 1750);
FORCEPROP 1 LAST PACK_TYPE 3018
J 0
(-6475 1800);
DISPLAY 0.617021 (-6475 1800);
PAINT SKYBLUE (-6475 1800);
FORCEPROP 1 LASTPIN (-6525 2050) $PN 1
J 0
(-6515 2035);
DISPLAY 0.787234 (-6515 2035);
PAINT ORANGE (-6515 2035);
FORCEPROP 1 LASTPIN (-6525 1850) $PN 2
J 0
(-6515 1835);
DISPLAY 0.787234 (-6515 1835);
PAINT ORANGE (-6515 1835);
FORCEPROP 1 LAST VOLTAGE 16V
J 0
(-6475 1900);
DISPLAY 0.617021 (-6475 1900);
PAINT SKYBLUE (-6475 1900);
FORCEPROP 1 LAST MATERIAL TANT
J 0
(-6475 1850);
DISPLAY 0.617021 (-6475 1850);
PAINT SKYBLUE (-6475 1850);
FORCEPROP 1 LAST TOLERANCE 20%
J 0
(-6475 1950);
DISPLAY 0.617021 (-6475 1950);
PAINT SKYBLUE (-6475 1950);
FORCEPROP 1 LAST VALUE 68UF
J 0
(-6475 2000);
DISPLAY 0.617021 (-6475 2000);
PAINT SKYBLUE (-6475 2000);
FORCEPROP 1 LAST LOCATION C6N5
J 0
(-6475 2050);
DISPLAY 0.617021 (-6475 2050);
PAINT AQUA (-6475 2050);
FORCEPROP 2 LAST SEC_TYPE 3018
J 0
(-6475 2150);
DISPLAY 1.021277 (-6475 2150);
PAINT ORANGE (-6475 2150);
DISPLAY INVISIBLE (-6475 2150);
FORCEPROP 2 LAST SEC 1
J 0
(-6475 2150);
PAINT MONO (-6475 2150);
DISPLAY INVISIBLE (-6475 2150);
FORCEPROP 2 LAST CDS_LIB mstr_discrete
J 0
(-6525 1950);
PAINT MONO (-6525 1950);
DISPLAY INVISIBLE (-6525 1950);
FORCEPROP 1 LAST PATH I109
J 0
(-6475 2100);
DISPLAY 0.978723 (-6475 2100);
PAINT ORANGE (-6475 2100);
DISPLAY INVISIBLE (-6475 2100);
FORCEPROP 2 LAST CDS_LOCATION C6N5
J 0
(-6475 2050);
DISPLAY 0.617021 (-6475 2050);
PAINT AQUA (-6475 2050);
DISPLAY INVISIBLE (-6475 2050);
FORCEADD GND..1
(-6375 1500);
FORCEPROP 3 LASTPIN (-6375 1550) SIG_NAME GND\g
J 0
(-6365 1560);
DISPLAY 0.659574 (-6365 1560);
PAINT MONO (-6365 1560);
DISPLAY INVISIBLE (-6365 1560);
FORCEPROP 1 LAST VOLTAGE 0.0V
J 0
(-6420 1457);
DISPLAY 0.340426 (-6420 1457);
PAINT SKYBLUE (-6420 1457);
DISPLAY INVISIBLE (-6420 1457);
FORCEPROP 1 LAST SIZE 1B
J 0
(-6300 1450);
DISPLAY 0.872340 (-6300 1450);
PAINT AQUA (-6300 1450);
DISPLAY INVISIBLE (-6300 1450);
FORCEPROP 1 LAST PATH I110
J 0
(-6300 1500);
DISPLAY 0.872340 (-6300 1500);
PAINT AQUA (-6300 1500);
DISPLAY INVISIBLE (-6300 1500);
FORCEPROP 2 LAST CDS_LIB mstr_symbols
J 0
(-6375 1500);
PAINT MONO (-6375 1500);
DISPLAY INVISIBLE (-6375 1500);
FORCEPROP 1 LAST BODY_TYPE PLUMBING
J 0
(-6420 1457);
DISPLAY 0.340426 (-6420 1457);
PAINT GREEN (-6420 1457);
DISPLAY INVISIBLE (-6420 1457);
FORCEPROP 1 LAST HDL_POWER GND
J 0
(-6375 1650);
DISPLAY 0.872340 (-6375 1650);
PAINT GREEN (-6375 1650);
DISPLAY INVISIBLE (-6375 1650);
FORCEADD CAPP..1
(-6875 1950);
FORCEPROP 1 LAST PART_NUMBER 724613-112
J 0
(-6825 1750);
DISPLAY 0.617021 (-6825 1750);
PAINT BLUE (-6825 1750);
FORCEPROP 1 LASTPIN (-6875 2050) $PN 1
J 0
(-6865 2035);
DISPLAY 0.787234 (-6865 2035);
PAINT ORANGE (-6865 2035);
FORCEPROP 1 LASTPIN (-6875 1850) $PN 2
J 0
(-6865 1835);
DISPLAY 0.787234 (-6865 1835);
PAINT ORANGE (-6865 1835);
FORCEPROP 1 LAST PACK_TYPE 3018
J 0
(-6825 1800);
DISPLAY 0.617021 (-6825 1800);
PAINT SKYBLUE (-6825 1800);
FORCEPROP 1 LAST MATERIAL TANT
J 0
(-6825 1850);
DISPLAY 0.617021 (-6825 1850);
PAINT SKYBLUE (-6825 1850);
FORCEPROP 1 LAST VOLTAGE 16V
J 0
(-6825 1900);
DISPLAY 0.617021 (-6825 1900);
PAINT SKYBLUE (-6825 1900);
FORCEPROP 1 LAST TOLERANCE 20%
J 0
(-6825 1950);
DISPLAY 0.617021 (-6825 1950);
PAINT SKYBLUE (-6825 1950);
FORCEPROP 1 LAST VALUE 68UF
J 0
(-6825 2000);
DISPLAY 0.617021 (-6825 2000);
PAINT SKYBLUE (-6825 2000);
FORCEPROP 1 LAST LOCATION C9T3
J 0
(-6825 2050);
DISPLAY 0.617021 (-6825 2050);
PAINT AQUA (-6825 2050);
FORCEPROP 2 LAST SEC_TYPE 3018
J 0
(-6825 2150);
DISPLAY 1.021277 (-6825 2150);
PAINT ORANGE (-6825 2150);
DISPLAY INVISIBLE (-6825 2150);
FORCEPROP 2 LAST SEC 1
J 0
(-6825 2150);
PAINT MONO (-6825 2150);
DISPLAY INVISIBLE (-6825 2150);
FORCEPROP 2 LAST CDS_LIB mstr_discrete
J 0
(-6875 1950);
PAINT MONO (-6875 1950);
DISPLAY INVISIBLE (-6875 1950);
FORCEPROP 1 LAST PATH I111
J 0
(-6825 2100);
DISPLAY 0.978723 (-6825 2100);
PAINT ORANGE (-6825 2100);
DISPLAY INVISIBLE (-6825 2100);
FORCEPROP 2 LAST CDS_LOCATION C9T3
J 0
(-6825 2050);
DISPLAY 0.617021 (-6825 2050);
PAINT AQUA (-6825 2050);
DISPLAY INVISIBLE (-6825 2050);
FORCEADD CAPP..1
(-7250 1950);
FORCEPROP 1 LASTPIN (-7250 2050) $PN 1
J 0
(-7240 2035);
DISPLAY 0.787234 (-7240 2035);
PAINT ORANGE (-7240 2035);
FORCEPROP 1 LASTPIN (-7250 1850) $PN 2
J 0
(-7240 1835);
DISPLAY 0.787234 (-7240 1835);
PAINT ORANGE (-7240 1835);
FORCEPROP 1 LAST PACK_TYPE 3018
J 0
(-7200 1800);
DISPLAY 0.617021 (-7200 1800);
PAINT SKYBLUE (-7200 1800);
FORCEPROP 1 LAST TOLERANCE 20%
J 0
(-7200 1950);
DISPLAY 0.617021 (-7200 1950);
PAINT SKYBLUE (-7200 1950);
FORCEPROP 1 LAST VOLTAGE 16V
J 0
(-7200 1900);
DISPLAY 0.617021 (-7200 1900);
PAINT SKYBLUE (-7200 1900);
FORCEPROP 1 LAST MATERIAL TANT
J 0
(-7200 1850);
DISPLAY 0.617021 (-7200 1850);
PAINT SKYBLUE (-7200 1850);
FORCEPROP 1 LAST PART_NUMBER 724613-112
J 0
(-7200 1750);
DISPLAY 0.617021 (-7200 1750);
PAINT BLUE (-7200 1750);
FORCEPROP 1 LAST VALUE 68UF
J 0
(-7200 2000);
DISPLAY 0.617021 (-7200 2000);
PAINT SKYBLUE (-7200 2000);
FORCEPROP 1 LAST LOCATION C4F4
J 0
(-7200 2050);
DISPLAY 0.617021 (-7200 2050);
PAINT AQUA (-7200 2050);
FORCEPROP 2 LAST SEC_TYPE 3018
J 0
(-7200 2150);
DISPLAY 1.021277 (-7200 2150);
PAINT ORANGE (-7200 2150);
DISPLAY INVISIBLE (-7200 2150);
FORCEPROP 2 LAST SEC 1
J 0
(-7200 2150);
PAINT MONO (-7200 2150);
DISPLAY INVISIBLE (-7200 2150);
FORCEPROP 2 LAST CDS_LIB mstr_discrete
J 0
(-7250 1950);
PAINT MONO (-7250 1950);
DISPLAY INVISIBLE (-7250 1950);
FORCEPROP 2 LAST CDS_LOCATION C4F4
J 0
(-7200 2050);
DISPLAY 0.617021 (-7200 2050);
PAINT AQUA (-7200 2050);
DISPLAY INVISIBLE (-7200 2050);
FORCEPROP 1 LAST PATH I112
J 0
(-7200 2100);
DISPLAY 0.978723 (-7200 2100);
PAINT ORANGE (-7200 2100);
DISPLAY INVISIBLE (-7200 2100);
FORCEADD CAPP..1
(-7675 1950);
FORCEPROP 1 LASTPIN (-7675 2050) $PN 1
J 0
(-7665 2035);
DISPLAY 0.787234 (-7665 2035);
PAINT ORANGE (-7665 2035);
FORCEPROP 1 LASTPIN (-7675 1850) $PN 2
J 0
(-7665 1835);
DISPLAY 0.787234 (-7665 1835);
PAINT ORANGE (-7665 1835);
FORCEPROP 1 LAST PACK_TYPE 3018
J 0
(-7625 1800);
DISPLAY 0.617021 (-7625 1800);
PAINT SKYBLUE (-7625 1800);
FORCEPROP 1 LAST VALUE 68UF
J 0
(-7625 2000);
DISPLAY 0.617021 (-7625 2000);
PAINT SKYBLUE (-7625 2000);
FORCEPROP 1 LAST TOLERANCE 20%
J 0
(-7625 1950);
DISPLAY 0.617021 (-7625 1950);
PAINT SKYBLUE (-7625 1950);
FORCEPROP 1 LAST VOLTAGE 16V
J 0
(-7625 1900);
DISPLAY 0.617021 (-7625 1900);
PAINT SKYBLUE (-7625 1900);
FORCEPROP 1 LAST MATERIAL TANT
J 0
(-7625 1850);
DISPLAY 0.617021 (-7625 1850);
PAINT SKYBLUE (-7625 1850);
FORCEPROP 1 LAST PART_NUMBER 724613-112
J 0
(-7625 1750);
DISPLAY 0.617021 (-7625 1750);
PAINT BLUE (-7625 1750);
FORCEPROP 1 LAST LOCATION C3T3
J 0
(-7625 2050);
DISPLAY 0.617021 (-7625 2050);
PAINT AQUA (-7625 2050);
FORCEPROP 2 LAST SEC_TYPE 3018
J 0
(-7625 2150);
DISPLAY 1.021277 (-7625 2150);
PAINT ORANGE (-7625 2150);
DISPLAY INVISIBLE (-7625 2150);
FORCEPROP 2 LAST SEC 1
J 0
(-7625 2150);
PAINT MONO (-7625 2150);
DISPLAY INVISIBLE (-7625 2150);
FORCEPROP 2 LAST CDS_LIB mstr_discrete
J 0
(-7675 1950);
PAINT MONO (-7675 1950);
DISPLAY INVISIBLE (-7675 1950);
FORCEPROP 2 LAST CDS_LOCATION C3T3
J 0
(-7625 2050);
DISPLAY 0.617021 (-7625 2050);
PAINT AQUA (-7625 2050);
DISPLAY INVISIBLE (-7625 2050);
FORCEPROP 1 LAST PATH I113
J 0
(-7625 2100);
DISPLAY 0.978723 (-7625 2100);
PAINT ORANGE (-7625 2100);
DISPLAY INVISIBLE (-7625 2100);
FORCEADD FCI-CONN12-2R-GP..1
(-3025 2150);
FORCEPROP 2 LASTPIN (-3350 2250) $PN 2_1
J 2
(-3360 2260);
DISPLAY 0.808511 (-3360 2260);
PAINT ORANGE (-3360 2260);
FORCEPROP 2 LASTPIN (-3350 2300) $PN 2_2
J 2
(-3360 2310);
DISPLAY 0.808511 (-3360 2310);
PAINT ORANGE (-3360 2310);
FORCEPROP 2 LASTPIN (-3350 2350) $PN 2_3
J 2
(-3360 2360);
DISPLAY 0.808511 (-3360 2360);
PAINT ORANGE (-3360 2360);
FORCEPROP 2 LASTPIN (-3350 2050) $PN 3_1
J 2
(-3360 2060);
DISPLAY 0.808511 (-3360 2060);
PAINT ORANGE (-3360 2060);
FORCEPROP 2 LASTPIN (-3350 2100) $PN 3_2
J 2
(-3360 2110);
DISPLAY 0.808511 (-3360 2110);
PAINT ORANGE (-3360 2110);
FORCEPROP 2 LASTPIN (-2700 2250) $PN 1_1
J 0
(-2690 2260);
DISPLAY 0.808511 (-2690 2260);
PAINT ORANGE (-2690 2260);
FORCEPROP 2 LASTPIN (-2700 2300) $PN 1_2
J 0
(-2690 2310);
DISPLAY 0.808511 (-2690 2310);
PAINT ORANGE (-2690 2310);
FORCEPROP 2 LASTPIN (-2700 2350) $PN 1_3
J 0
(-2690 2360);
DISPLAY 0.808511 (-2690 2360);
PAINT ORANGE (-2690 2360);
FORCEPROP 2 LASTPIN (-2700 2050) $PN 4_1
J 0
(-2690 2060);
DISPLAY 0.808511 (-2690 2060);
PAINT ORANGE (-2690 2060);
FORCEPROP 2 LASTPIN (-2700 2100) $PN 4_2
J 0
(-2690 2110);
DISPLAY 0.808511 (-2690 2110);
PAINT ORANGE (-2690 2110);
FORCEPROP 2 LASTPIN (-2700 2150) $PN 4_3
J 0
(-2690 2160);
DISPLAY 0.808511 (-2690 2160);
PAINT ORANGE (-2690 2160);
FORCEPROP 1 LAST VALUE FCI-CONN12-2R-GP
J 0
(-3175 1800);
DISPLAY 0.617021 (-3175 1800);
PAINT GREEN (-3175 1800);
FORCEPROP 2 LASTPIN (-3350 2150) $PN 3_3
J 2
(-3360 2160);
DISPLAY 0.808511 (-3360 2160);
PAINT ORANGE (-3360 2160);
FORCEPROP 1 LAST LOCATION J1E1
J 0
(-3175 2475);
DISPLAY 0.617021 (-3175 2475);
PAINT GREEN (-3175 2475);
FORCEPROP 2 LASTPIN (-2800 1950) $PN NP1
J 0
(-2790 1960);
DISPLAY 0.808511 (-2790 1960);
PAINT ORANGE (-2790 1960);
FORCEPROP 1 LAST CDS_LMAN_SYM_OUTLINE -175,300,175,-300
J 0
(-3025 2150);
DISPLAY 0.468085 (-3025 2150);
PAINT GREEN (-3025 2150);
DISPLAY INVISIBLE (-3025 2150);
FORCEPROP 2 LAST CDS_LIB w_hdl
J 0
(-3025 2150);
PAINT MONO (-3025 2150);
DISPLAY INVISIBLE (-3025 2150);
FORCEPROP 1 LAST PART_NUMBER 20.82093.012
J 0
(-3025 2110);
DISPLAY 0.617021 (-3025 2110);
PAINT GREEN (-3025 2110);
DISPLAY INVISIBLE (-3025 2110);
FORCEPROP 2 LAST SEC_TYPE CONN-G5
J 0
(-3175 2525);
DISPLAY 1.021277 (-3175 2525);
PAINT ORANGE (-3175 2525);
DISPLAY INVISIBLE (-3175 2525);
FORCEPROP 2 LAST SEC 1
J 0
(-3175 2525);
DISPLAY 0.680851 (-3175 2525);
PAINT MONO (-3175 2525);
DISPLAY INVISIBLE (-3175 2525);
FORCEPROP 1 LAST PACK_TYPE CONN-G5
J 0
(-3025 2150);
DISPLAY 0.617021 (-3025 2150);
PAINT GREEN (-3025 2150);
DISPLAY INVISIBLE (-3025 2150);
FORCEPROP 1 LAST PATH I114
J 0
(-3025 2190);
DISPLAY 0.617021 (-3025 2190);
PAINT GREEN (-3025 2190);
DISPLAY INVISIBLE (-3025 2190);
FORCEADD FCI-CONN12-2R-GP..1
(-1250 2150);
FORCEPROP 0 LAST POP NOPOP
J 0
(-1400 2525);
DISPLAY 1.021277 (-1400 2525);
PAINT RED (-1400 2525);
FORCEPROP 2 LASTPIN (-1025 1950) $PN NP1
J 0
(-1015 1960);
DISPLAY 0.808511 (-1015 1960);
PAINT ORANGE (-1015 1960);
FORCEPROP 2 LASTPIN (-1575 2150) $PN 3_3
J 2
(-1585 2160);
DISPLAY 0.808511 (-1585 2160);
PAINT ORANGE (-1585 2160);
FORCEPROP 1 LAST VALUE FCI-CONN12-2R-GP
J 0
(-1400 1800);
DISPLAY 0.617021 (-1400 1800);
PAINT GREEN (-1400 1800);
FORCEPROP 2 LASTPIN (-925 2150) $PN 4_3
J 0
(-915 2160);
DISPLAY 0.808511 (-915 2160);
PAINT ORANGE (-915 2160);
FORCEPROP 2 LASTPIN (-925 2100) $PN 4_2
J 0
(-915 2110);
DISPLAY 0.808511 (-915 2110);
PAINT ORANGE (-915 2110);
FORCEPROP 2 LASTPIN (-925 2050) $PN 4_1
J 0
(-915 2060);
DISPLAY 0.808511 (-915 2060);
PAINT ORANGE (-915 2060);
FORCEPROP 2 LASTPIN (-925 2350) $PN 1_3
J 0
(-915 2360);
DISPLAY 0.808511 (-915 2360);
PAINT ORANGE (-915 2360);
FORCEPROP 2 LASTPIN (-925 2300) $PN 1_2
J 0
(-915 2310);
DISPLAY 0.808511 (-915 2310);
PAINT ORANGE (-915 2310);
FORCEPROP 2 LASTPIN (-925 2250) $PN 1_1
J 0
(-915 2260);
DISPLAY 0.808511 (-915 2260);
PAINT ORANGE (-915 2260);
FORCEPROP 2 LASTPIN (-1575 2100) $PN 3_2
J 2
(-1585 2110);
DISPLAY 0.808511 (-1585 2110);
PAINT ORANGE (-1585 2110);
FORCEPROP 2 LASTPIN (-1575 2050) $PN 3_1
J 2
(-1585 2060);
DISPLAY 0.808511 (-1585 2060);
PAINT ORANGE (-1585 2060);
FORCEPROP 2 LASTPIN (-1575 2350) $PN 2_3
J 2
(-1585 2360);
DISPLAY 0.808511 (-1585 2360);
PAINT ORANGE (-1585 2360);
FORCEPROP 2 LASTPIN (-1575 2300) $PN 2_2
J 2
(-1585 2310);
DISPLAY 0.808511 (-1585 2310);
PAINT ORANGE (-1585 2310);
FORCEPROP 2 LASTPIN (-1575 2250) $PN 2_1
J 2
(-1585 2260);
DISPLAY 0.808511 (-1585 2260);
PAINT ORANGE (-1585 2260);
FORCEPROP 1 LAST LOCATION J1D1
J 0
(-1400 2475);
DISPLAY 0.617021 (-1400 2475);
PAINT GREEN (-1400 2475);
FORCEPROP 1 LAST PACK_TYPE CONN-G5
J 0
(-1250 2150);
DISPLAY 0.617021 (-1250 2150);
PAINT GREEN (-1250 2150);
DISPLAY INVISIBLE (-1250 2150);
FORCEPROP 2 LAST SEC 1
J 0
(-1400 2525);
DISPLAY 0.680851 (-1400 2525);
PAINT MONO (-1400 2525);
DISPLAY INVISIBLE (-1400 2525);
FORCEPROP 2 LAST SEC_TYPE CONN-G5
J 0
(-1400 2525);
DISPLAY 1.021277 (-1400 2525);
PAINT ORANGE (-1400 2525);
DISPLAY INVISIBLE (-1400 2525);
FORCEPROP 1 LAST PART_NUMBER 20.82093.012
J 0
(-1250 2110);
DISPLAY 0.617021 (-1250 2110);
PAINT GREEN (-1250 2110);
DISPLAY INVISIBLE (-1250 2110);
FORCEPROP 2 LAST CDS_LIB w_hdl
J 0
(-1250 2150);
PAINT MONO (-1250 2150);
DISPLAY INVISIBLE (-1250 2150);
FORCEPROP 1 LAST CDS_LMAN_SYM_OUTLINE -175,300,175,-300
J 0
(-1250 2150);
DISPLAY 0.468085 (-1250 2150);
PAINT GREEN (-1250 2150);
DISPLAY INVISIBLE (-1250 2150);
FORCEPROP 1 LAST PATH I115
J 0
(-1250 2190);
DISPLAY 0.617021 (-1250 2190);
PAINT GREEN (-1250 2190);
DISPLAY INVISIBLE (-1250 2190);
FORCEADD STFT363B238R224H453-GP..1
(-7650 4750);
FORCEPROP 1 LAST LOCATION RM1G1
J 0
(-7750 4860);
DISPLAY 0.617021 (-7750 4860);
PAINT GREEN (-7750 4860);
FORCEPROP 1 LAST VALUE STFT363B238R224H453-GP
J 0
(-7750 4565);
DISPLAY 0.617021 (-7750 4565);
PAINT GREEN (-7750 4565);
FORCEPROP 2 LASTPIN (-7400 4750) $PN 1
J 0
(-7390 4760);
DISPLAY 0.808511 (-7390 4760);
PAINT ORANGE (-7390 4760);
FORCEPROP 1 LAST CDS_LMAN_SYM_OUTLINE -100,100,100,-100
J 0
(-7650 4750);
DISPLAY 0.468085 (-7650 4750);
PAINT GREEN (-7650 4750);
DISPLAY INVISIBLE (-7650 4750);
FORCEPROP 1 LAST PATH I117
J 0
(-7650 4790);
DISPLAY 0.617021 (-7650 4790);
PAINT GREEN (-7650 4790);
DISPLAY INVISIBLE (-7650 4790);
FORCEPROP 2 LAST CDS_LIB w_hdl
J 0
(-7650 4750);
PAINT MONO (-7650 4750);
DISPLAY INVISIBLE (-7650 4750);
FORCEPROP 1 LAST PART_NUMBER 086.2AT24.04R6
J 0
(-7650 4710);
DISPLAY 0.617021 (-7650 4710);
PAINT GREEN (-7650 4710);
DISPLAY INVISIBLE (-7650 4710);
FORCEPROP 1 LAST PACK_TYPE DISCRET-GC1
J 0
(-7650 4750);
DISPLAY 0.617021 (-7650 4750);
PAINT GREEN (-7650 4750);
DISPLAY INVISIBLE (-7650 4750);
FORCEPROP 2 LAST SEC 1
J 0
(-7750 4900);
DISPLAY 0.680851 (-7750 4900);
PAINT MONO (-7750 4900);
DISPLAY INVISIBLE (-7750 4900);
FORCEPROP 2 LAST SEC_TYPE DISCRET-GC1
J 0
(-7750 4900);
DISPLAY 1.021277 (-7750 4900);
PAINT ORANGE (-7750 4900);
DISPLAY INVISIBLE (-7750 4900);
FORCEADD GND..1
(-7350 4650);
FORCEPROP 3 LASTPIN (-7350 4700) SIG_NAME GND\g
J 0
(-7340 4710);
DISPLAY 0.659574 (-7340 4710);
PAINT MONO (-7340 4710);
DISPLAY INVISIBLE (-7340 4710);
FORCEPROP 1 LAST PATH I118
J 0
(-7275 4650);
DISPLAY 0.872340 (-7275 4650);
PAINT AQUA (-7275 4650);
DISPLAY INVISIBLE (-7275 4650);
FORCEPROP 1 LAST VOLTAGE 0.0V
J 0
(-7395 4607);
DISPLAY 0.340426 (-7395 4607);
PAINT SKYBLUE (-7395 4607);
DISPLAY INVISIBLE (-7395 4607);
FORCEPROP 2 LAST CDS_LIB mstr_symbols
J 0
(-7350 4650);
PAINT ORANGE (-7350 4650);
DISPLAY INVISIBLE (-7350 4650);
FORCEPROP 1 LAST SIZE 1B
J 0
(-7275 4600);
DISPLAY 0.872340 (-7275 4600);
PAINT AQUA (-7275 4600);
DISPLAY INVISIBLE (-7275 4600);
FORCEPROP 1 LAST BODY_TYPE PLUMBING
J 0
(-7395 4607);
DISPLAY 0.340426 (-7395 4607);
PAINT GREEN (-7395 4607);
DISPLAY INVISIBLE (-7395 4607);
FORCEPROP 1 LAST HDL_POWER GND
J 0
(-7350 4800);
DISPLAY 0.872340 (-7350 4800);
PAINT GREEN (-7350 4800);
DISPLAY INVISIBLE (-7350 4800);
FORCEADD P12V_PSU..1
(-3700 2750);
FORCEPROP 3 LASTPIN (-3700 2700) SIG_NAME P12V_PSU\g
J 0
(-3690 2710);
DISPLAY 0.659574 (-3690 2710);
PAINT MONO (-3690 2710);
DISPLAY INVISIBLE (-3690 2710);
FORCEPROP 1 LAST VOLTAGE 12.0
J 0
(-3745 2707);
DISPLAY 0.340426 (-3745 2707);
PAINT SKYBLUE (-3745 2707);
DISPLAY INVISIBLE (-3745 2707);
FORCEPROP 2 LAST BOM_COST NT_BASE_VRD
J 0
(-3700 2850);
DISPLAY 0.617021 (-3700 2850);
PAINT ORANGE (-3700 2850);
DISPLAY INVISIBLE (-3700 2850);
FORCEPROP 2 LAST CDS_LIB mstr_symbols
J 0
(-3700 2750);
PAINT ORANGE (-3700 2750);
DISPLAY INVISIBLE (-3700 2750);
FORCEPROP 1 LAST PATH I25
J 0
(-3650 2775);
DISPLAY 0.872340 (-3650 2775);
PAINT AQUA (-3650 2775);
DISPLAY INVISIBLE (-3650 2775);
FORCEPROP 2 LAST ROOM P2V5_LAN_AUX_VR
J 0
(-3700 2850);
DISPLAY 0.617021 (-3700 2850);
PAINT ORANGE (-3700 2850);
DISPLAY INVISIBLE (-3700 2850);
FORCEPROP 1 LAST BODY_TYPE PLUMBING
J 0
(-3745 2707);
DISPLAY 0.340426 (-3745 2707);
PAINT GREEN (-3745 2707);
DISPLAY INVISIBLE (-3745 2707);
FORCEPROP 1 LAST HDL_POWER P12V_PSU
J 1
(-3700 2800);
DISPLAY 0.872340 (-3700 2800);
PAINT GREEN (-3700 2800);
DISPLAY INVISIBLE (-3700 2800);
FORCEADD CONN3_G98259001..1
(-925 3725);
FORCEPROP 1 LAST PART_NUMBER G98259-001
J 0
(-1075 3475);
DISPLAY 0.617021 (-1075 3475);
PAINT BLUE (-1075 3475);
FORCEPROP 1 LAST MATERIAL CONN
J 0
(-1075 3950);
DISPLAY 0.617021 (-1075 3950);
PAINT SKYBLUE (-1075 3950);
FORCEPROP 1 LAST LOCATION RM1E1
J 0
(-1075 4000);
DISPLAY 0.617021 (-1075 4000);
PAINT AQUA (-1075 4000);
FORCEPROP 2 LASTPIN (-725 3675) $PN 3
J 0
(-715 3685);
DISPLAY 0.617021 (-715 3685);
PAINT MONO (-715 3685);
FORCEPROP 2 LASTPIN (-725 3575) $PN 2
J 0
(-715 3585);
DISPLAY 0.617021 (-715 3585);
PAINT MONO (-715 3585);
FORCEPROP 2 LASTPIN (-725 3775) $PN 1
J 0
(-715 3785);
DISPLAY 0.617021 (-715 3785);
PAINT MONO (-715 3785);
FORCEPROP 2 LAST CDS_LOCATION RM1E1
J 0
(-1075 4000);
DISPLAY 0.617021 (-1075 4000);
PAINT AQUA (-1075 4000);
DISPLAY INVISIBLE (-1075 4000);
FORCEPROP 2 LAST $SEC 1
J 0
(-1075 4050);
PAINT MONO (-1075 4050);
DISPLAY INVISIBLE (-1075 4050);
FORCEPROP 2 LAST CDS_SEC 1
J 0
(-1075 4050);
PAINT MONO (-1075 4050);
DISPLAY INVISIBLE (-1075 4050);
FORCEPROP 1 LAST PACK_TYPE PIP
J 0
(-1075 4050);
PAINT SKYBLUE (-1075 4050);
DISPLAY INVISIBLE (-1075 4050);
FORCEPROP 1 LAST CDS_LMAN_SYM_OUTLINE -150,200,150,-200
J 0
(-925 3725);
DISPLAY 0.468085 (-925 3725);
PAINT GREEN (-925 3725);
DISPLAY INVISIBLE (-925 3725);
FORCEPROP 2 LAST CDS_LIB mstr_conn
J 0
(-925 3725);
PAINT ORANGE (-925 3725);
DISPLAY INVISIBLE (-925 3725);
FORCEPROP 1 LAST PATH I26
J 0
(-825 3951);
PAINT GREEN (-825 3951);
DISPLAY INVISIBLE (-825 3951);
FORCEADD GND..1
(-475 3375);
FORCEPROP 3 LASTPIN (-475 3425) SIG_NAME GND\g
J 0
(-465 3435);
DISPLAY 0.659574 (-465 3435);
PAINT MONO (-465 3435);
DISPLAY INVISIBLE (-465 3435);
FORCEPROP 1 LAST VOLTAGE 0.0V
J 0
(-520 3332);
DISPLAY 0.340426 (-520 3332);
PAINT SKYBLUE (-520 3332);
DISPLAY INVISIBLE (-520 3332);
FORCEPROP 1 LAST SIZE 1B
J 0
(-400 3325);
DISPLAY 0.872340 (-400 3325);
PAINT AQUA (-400 3325);
DISPLAY INVISIBLE (-400 3325);
FORCEPROP 2 LAST CDS_LIB mstr_symbols
J 0
(-475 3375);
PAINT ORANGE (-475 3375);
DISPLAY INVISIBLE (-475 3375);
FORCEPROP 1 LAST PATH I27
J 0
(-400 3375);
DISPLAY 0.872340 (-400 3375);
PAINT AQUA (-400 3375);
DISPLAY INVISIBLE (-400 3375);
FORCEPROP 1 LAST BODY_TYPE PLUMBING
J 0
(-520 3332);
DISPLAY 0.340426 (-520 3332);
PAINT GREEN (-520 3332);
DISPLAY INVISIBLE (-520 3332);
FORCEPROP 1 LAST HDL_POWER GND
J 0
(-475 3525);
DISPLAY 0.872340 (-475 3525);
PAINT GREEN (-475 3525);
DISPLAY INVISIBLE (-475 3525);
FORCEADD GND..1
(-3550 1900);
FORCEPROP 3 LASTPIN (-3550 1950) SIG_NAME GND\g
J 0
(-3540 1960);
DISPLAY 0.659574 (-3540 1960);
PAINT MONO (-3540 1960);
DISPLAY INVISIBLE (-3540 1960);
FORCEPROP 1 LAST VOLTAGE 0.0V
J 0
(-3595 1857);
DISPLAY 0.340426 (-3595 1857);
PAINT SKYBLUE (-3595 1857);
DISPLAY INVISIBLE (-3595 1857);
FORCEPROP 1 LAST SIZE 1B
J 0
(-3475 1850);
DISPLAY 0.872340 (-3475 1850);
PAINT AQUA (-3475 1850);
DISPLAY INVISIBLE (-3475 1850);
FORCEPROP 2 LAST CDS_LIB mstr_symbols
J 0
(-3550 1900);
PAINT ORANGE (-3550 1900);
DISPLAY INVISIBLE (-3550 1900);
FORCEPROP 1 LAST PATH I28
J 0
(-3475 1900);
DISPLAY 0.872340 (-3475 1900);
PAINT AQUA (-3475 1900);
DISPLAY INVISIBLE (-3475 1900);
FORCEPROP 1 LAST BODY_TYPE PLUMBING
J 0
(-3595 1857);
DISPLAY 0.340426 (-3595 1857);
PAINT GREEN (-3595 1857);
DISPLAY INVISIBLE (-3595 1857);
FORCEPROP 1 LAST HDL_POWER GND
J 0
(-3550 2050);
DISPLAY 0.872340 (-3550 2050);
PAINT GREEN (-3550 2050);
DISPLAY INVISIBLE (-3550 2050);
FORCEADD GND..1
(-3700 3225);
FORCEPROP 3 LASTPIN (-3700 3275) SIG_NAME GND\g
J 0
(-3690 3285);
DISPLAY 0.659574 (-3690 3285);
PAINT MONO (-3690 3285);
DISPLAY INVISIBLE (-3690 3285);
FORCEPROP 1 LAST VOLTAGE 0.0V
J 0
(-3745 3182);
DISPLAY 0.340426 (-3745 3182);
PAINT SKYBLUE (-3745 3182);
DISPLAY INVISIBLE (-3745 3182);
FORCEPROP 1 LAST SIZE 1B
J 0
(-3625 3175);
DISPLAY 0.872340 (-3625 3175);
PAINT AQUA (-3625 3175);
DISPLAY INVISIBLE (-3625 3175);
FORCEPROP 1 LAST PATH I30
J 0
(-3625 3225);
DISPLAY 0.872340 (-3625 3225);
PAINT AQUA (-3625 3225);
DISPLAY INVISIBLE (-3625 3225);
FORCEPROP 2 LAST CDS_LIB mstr_symbols
J 0
(-3700 3225);
PAINT ORANGE (-3700 3225);
DISPLAY INVISIBLE (-3700 3225);
FORCEPROP 1 LAST BODY_TYPE PLUMBING
J 0
(-3745 3182);
DISPLAY 0.340426 (-3745 3182);
PAINT GREEN (-3745 3182);
DISPLAY INVISIBLE (-3745 3182);
FORCEPROP 1 LAST HDL_POWER GND
J 0
(-3700 3375);
DISPLAY 0.872340 (-3700 3375);
PAINT GREEN (-3700 3375);
DISPLAY INVISIBLE (-3700 3375);
FORCEADD CAP..1
(-3700 3650);
FORCEPROP 1 LAST VOLTAGE 16V
J 0
(-3650 3650);
DISPLAY 0.617021 (-3650 3650);
PAINT SKYBLUE (-3650 3650);
FORCEPROP 1 LAST PART_NUMBER C95333-007
J 0
(-3650 3500);
DISPLAY 0.617021 (-3650 3500);
PAINT BLUE (-3650 3500);
FORCEPROP 0 LAST POP NOPOP
J 0
(-3650 3400);
DISPLAY 0.638298 (-3650 3400);
PAINT RED (-3650 3400);
FORCEPROP 1 LAST TOLERANCE 10%
J 0
(-3650 3600);
DISPLAY 0.617021 (-3650 3600);
PAINT SKYBLUE (-3650 3600);
FORCEPROP 1 LAST VALUE 10UF
J 0
(-3650 3700);
DISPLAY 0.617021 (-3650 3700);
PAINT SKYBLUE (-3650 3700);
FORCEPROP 1 LASTPIN (-3700 3750) $PN 1
J 0
(-3690 3730);
DISPLAY 0.617021 (-3690 3730);
PAINT ORANGE (-3690 3730);
FORCEPROP 1 LASTPIN (-3700 3550) $PN 2
J 0
(-3690 3530);
DISPLAY 0.617021 (-3690 3530);
PAINT ORANGE (-3690 3530);
FORCEPROP 1 LAST PACK_TYPE 0805
J 0
(-3650 3450);
DISPLAY 0.617021 (-3650 3450);
PAINT SKYBLUE (-3650 3450);
FORCEPROP 1 LAST MATERIAL X6S
J 0
(-3650 3550);
DISPLAY 0.617021 (-3650 3550);
PAINT SKYBLUE (-3650 3550);
FORCEPROP 1 LAST LOCATION C9R5
J 0
(-3650 3750);
DISPLAY 0.617021 (-3650 3750);
PAINT AQUA (-3650 3750);
FORCEPROP 2 LAST SEC_TYPE 0805
J 0
(-3650 3850);
DISPLAY 1.021277 (-3650 3850);
PAINT ORANGE (-3650 3850);
DISPLAY INVISIBLE (-3650 3850);
FORCEPROP 2 LAST SEC 1
J 0
(-3650 3850);
DISPLAY 0.680851 (-3650 3850);
PAINT MONO (-3650 3850);
DISPLAY INVISIBLE (-3650 3850);
FORCEPROP 1 LAST PATH I31
J 0
(-3650 3800);
DISPLAY 0.978723 (-3650 3800);
PAINT WHITE (-3650 3800);
DISPLAY INVISIBLE (-3650 3800);
FORCEPROP 2 LAST ROOM HOT_SWAP
J 0
(-3650 3800);
DISPLAY 1.361702 (-3650 3800);
PAINT ORANGE (-3650 3800);
DISPLAY INVISIBLE (-3650 3800);
FORCEPROP 2 LAST CDS_LIB mstr_discrete
J 0
(-3700 3650);
PAINT ORANGE (-3700 3650);
DISPLAY INVISIBLE (-3700 3650);
FORCEPROP 2 LAST CDS_LOCATION C9R5
J 0
(-3650 3750);
DISPLAY 0.617021 (-3650 3750);
PAINT AQUA (-3650 3750);
DISPLAY INVISIBLE (-3650 3750);
FORCEADD CAP..1
(-3375 3650);
FORCEPROP 0 LAST POP NOPOP
J 0
(-3325 3400);
DISPLAY 0.638298 (-3325 3400);
PAINT RED (-3325 3400);
FORCEPROP 1 LAST PART_NUMBER C95333-007
J 0
(-3325 3500);
DISPLAY 0.617021 (-3325 3500);
PAINT BLUE (-3325 3500);
FORCEPROP 1 LAST PACK_TYPE 0805
J 0
(-3325 3450);
DISPLAY 0.617021 (-3325 3450);
PAINT SKYBLUE (-3325 3450);
FORCEPROP 1 LAST TOLERANCE 10%
J 0
(-3325 3600);
DISPLAY 0.617021 (-3325 3600);
PAINT SKYBLUE (-3325 3600);
FORCEPROP 1 LAST VALUE 10UF
J 0
(-3325 3700);
DISPLAY 0.617021 (-3325 3700);
PAINT SKYBLUE (-3325 3700);
FORCEPROP 1 LAST LOCATION C1E12
J 0
(-3325 3750);
DISPLAY 0.617021 (-3325 3750);
PAINT AQUA (-3325 3750);
FORCEPROP 1 LASTPIN (-3375 3750) $PN 1
J 0
(-3365 3730);
DISPLAY 0.617021 (-3365 3730);
PAINT ORANGE (-3365 3730);
FORCEPROP 1 LAST MATERIAL X6S
J 0
(-3325 3550);
DISPLAY 0.617021 (-3325 3550);
PAINT SKYBLUE (-3325 3550);
FORCEPROP 1 LASTPIN (-3375 3550) $PN 2
J 0
(-3365 3530);
DISPLAY 0.617021 (-3365 3530);
PAINT ORANGE (-3365 3530);
FORCEPROP 1 LAST VOLTAGE 16V
J 0
(-3325 3650);
DISPLAY 0.617021 (-3325 3650);
PAINT SKYBLUE (-3325 3650);
FORCEPROP 2 LAST SEC_TYPE 0805
J 0
(-3325 3850);
DISPLAY 1.021277 (-3325 3850);
PAINT ORANGE (-3325 3850);
DISPLAY INVISIBLE (-3325 3850);
FORCEPROP 2 LAST SEC 1
J 0
(-3325 3850);
DISPLAY 0.680851 (-3325 3850);
PAINT MONO (-3325 3850);
DISPLAY INVISIBLE (-3325 3850);
FORCEPROP 2 LAST CDS_LOCATION C1E12
J 0
(-3325 3750);
DISPLAY 0.617021 (-3325 3750);
PAINT AQUA (-3325 3750);
DISPLAY INVISIBLE (-3325 3750);
FORCEPROP 1 LAST PATH I32
J 0
(-3325 3800);
DISPLAY 0.978723 (-3325 3800);
PAINT WHITE (-3325 3800);
DISPLAY INVISIBLE (-3325 3800);
FORCEPROP 2 LAST ROOM HOT_SWAP
J 0
(-3325 3800);
DISPLAY 1.361702 (-3325 3800);
PAINT ORANGE (-3325 3800);
DISPLAY INVISIBLE (-3325 3800);
FORCEPROP 2 LAST CDS_LIB mstr_discrete
J 0
(-3375 3650);
PAINT ORANGE (-3375 3650);
DISPLAY INVISIBLE (-3375 3650);
FORCEADD GND..1
(-2500 1900);
FORCEPROP 3 LASTPIN (-2500 1950) SIG_NAME GND\g
J 0
(-2490 1960);
DISPLAY 0.659574 (-2490 1960);
PAINT MONO (-2490 1960);
DISPLAY INVISIBLE (-2490 1960);
FORCEPROP 1 LAST VOLTAGE 0.0V
J 0
(-2545 1857);
DISPLAY 0.340426 (-2545 1857);
PAINT SKYBLUE (-2545 1857);
DISPLAY INVISIBLE (-2545 1857);
FORCEPROP 2 LAST CDS_LIB mstr_symbols
J 0
(-2500 1900);
PAINT ORANGE (-2500 1900);
DISPLAY INVISIBLE (-2500 1900);
FORCEPROP 1 LAST SIZE 1B
J 0
(-2425 1850);
DISPLAY 0.872340 (-2425 1850);
PAINT AQUA (-2425 1850);
DISPLAY INVISIBLE (-2425 1850);
FORCEPROP 1 LAST PATH I33
J 0
(-2425 1900);
DISPLAY 0.872340 (-2425 1900);
PAINT AQUA (-2425 1900);
DISPLAY INVISIBLE (-2425 1900);
FORCEPROP 1 LAST BODY_TYPE PLUMBING
J 0
(-2545 1857);
DISPLAY 0.340426 (-2545 1857);
PAINT GREEN (-2545 1857);
DISPLAY INVISIBLE (-2545 1857);
FORCEPROP 1 LAST HDL_POWER GND
J 0
(-2500 2050);
DISPLAY 0.872340 (-2500 2050);
PAINT GREEN (-2500 2050);
DISPLAY INVISIBLE (-2500 2050);
FORCEADD P12V_PSU..1
(-2350 2750);
FORCEPROP 3 LASTPIN (-2350 2700) SIG_NAME P12V_PSU\g
J 0
(-2340 2710);
DISPLAY 0.659574 (-2340 2710);
PAINT MONO (-2340 2710);
DISPLAY INVISIBLE (-2340 2710);
FORCEPROP 2 LAST ROOM P2V5_LAN_AUX_VR
J 0
(-2350 2850);
DISPLAY 0.617021 (-2350 2850);
PAINT ORANGE (-2350 2850);
DISPLAY INVISIBLE (-2350 2850);
FORCEPROP 1 LAST PATH I34
J 0
(-2300 2775);
DISPLAY 0.872340 (-2300 2775);
PAINT AQUA (-2300 2775);
DISPLAY INVISIBLE (-2300 2775);
FORCEPROP 2 LAST BOM_COST NT_BASE_VRD
J 0
(-2350 2850);
DISPLAY 0.617021 (-2350 2850);
PAINT ORANGE (-2350 2850);
DISPLAY INVISIBLE (-2350 2850);
FORCEPROP 2 LAST CDS_LIB mstr_symbols
J 0
(-2350 2750);
PAINT ORANGE (-2350 2750);
DISPLAY INVISIBLE (-2350 2750);
FORCEPROP 1 LAST VOLTAGE 12.0
J 0
(-2395 2707);
DISPLAY 0.340426 (-2395 2707);
PAINT SKYBLUE (-2395 2707);
DISPLAY INVISIBLE (-2395 2707);
FORCEPROP 1 LAST BODY_TYPE PLUMBING
J 0
(-2395 2707);
DISPLAY 0.340426 (-2395 2707);
PAINT GREEN (-2395 2707);
DISPLAY INVISIBLE (-2395 2707);
FORCEPROP 1 LAST HDL_POWER P12V_PSU
J 1
(-2350 2800);
DISPLAY 0.872340 (-2350 2800);
PAINT GREEN (-2350 2800);
DISPLAY INVISIBLE (-2350 2800);
FORCEADD CAP..1
(-3025 3650);
FORCEPROP 0 LAST POP NOPOP
J 0
(-2975 3400);
DISPLAY 0.638298 (-2975 3400);
PAINT RED (-2975 3400);
FORCEPROP 1 LAST LOCATION C1E15
J 0
(-2975 3750);
DISPLAY 0.617021 (-2975 3750);
PAINT AQUA (-2975 3750);
FORCEPROP 1 LASTPIN (-3025 3750) $PN 1
J 0
(-3015 3730);
DISPLAY 0.617021 (-3015 3730);
PAINT ORANGE (-3015 3730);
FORCEPROP 1 LAST VALUE 10UF
J 0
(-2975 3700);
DISPLAY 0.617021 (-2975 3700);
PAINT SKYBLUE (-2975 3700);
FORCEPROP 1 LAST TOLERANCE 10%
J 0
(-2975 3600);
DISPLAY 0.617021 (-2975 3600);
PAINT SKYBLUE (-2975 3600);
FORCEPROP 1 LAST VOLTAGE 16V
J 0
(-2975 3650);
DISPLAY 0.617021 (-2975 3650);
PAINT SKYBLUE (-2975 3650);
FORCEPROP 1 LAST MATERIAL X6S
J 0
(-2975 3550);
DISPLAY 0.617021 (-2975 3550);
PAINT SKYBLUE (-2975 3550);
FORCEPROP 1 LASTPIN (-3025 3550) $PN 2
J 0
(-3015 3530);
DISPLAY 0.617021 (-3015 3530);
PAINT ORANGE (-3015 3530);
FORCEPROP 1 LAST PACK_TYPE 0805
J 0
(-2975 3450);
DISPLAY 0.617021 (-2975 3450);
PAINT SKYBLUE (-2975 3450);
FORCEPROP 1 LAST PART_NUMBER C95333-007
J 0
(-2975 3500);
DISPLAY 0.617021 (-2975 3500);
PAINT BLUE (-2975 3500);
FORCEPROP 2 LAST SEC 1
J 0
(-2975 3850);
DISPLAY 0.680851 (-2975 3850);
PAINT MONO (-2975 3850);
DISPLAY INVISIBLE (-2975 3850);
FORCEPROP 2 LAST SEC_TYPE 0805
J 0
(-2975 3850);
DISPLAY 1.021277 (-2975 3850);
PAINT ORANGE (-2975 3850);
DISPLAY INVISIBLE (-2975 3850);
FORCEPROP 2 LAST ROOM HOT_SWAP
J 0
(-2975 3800);
DISPLAY 1.361702 (-2975 3800);
PAINT ORANGE (-2975 3800);
DISPLAY INVISIBLE (-2975 3800);
FORCEPROP 1 LAST PATH I35
J 0
(-2975 3800);
DISPLAY 0.978723 (-2975 3800);
PAINT WHITE (-2975 3800);
DISPLAY INVISIBLE (-2975 3800);
FORCEPROP 2 LAST CDS_LOCATION C1E15
J 0
(-2975 3750);
DISPLAY 0.617021 (-2975 3750);
PAINT AQUA (-2975 3750);
DISPLAY INVISIBLE (-2975 3750);
FORCEPROP 2 LAST CDS_LIB mstr_discrete
J 0
(-3025 3650);
PAINT ORANGE (-3025 3650);
DISPLAY INVISIBLE (-3025 3650);
FORCEADD CAP_A..1
(-2675 3650);
FORCEPROP 1 LAST LOCATION C9R12
J 0
(-2625 3750);
DISPLAY 0.617021 (-2625 3750);
PAINT AQUA (-2625 3750);
FORCEPROP 1 LAST VALUE 0.1UF
J 0
(-2625 3700);
DISPLAY 0.617021 (-2625 3700);
PAINT SKYBLUE (-2625 3700);
FORCEPROP 1 LAST VOLTAGE 16V
J 0
(-2625 3650);
DISPLAY 0.617021 (-2625 3650);
PAINT SKYBLUE (-2625 3650);
FORCEPROP 1 LAST TOLERANCE 10%
J 0
(-2625 3600);
DISPLAY 0.617021 (-2625 3600);
PAINT SKYBLUE (-2625 3600);
FORCEPROP 1 LAST MATERIAL X7R
J 0
(-2625 3550);
DISPLAY 0.617021 (-2625 3550);
PAINT SKYBLUE (-2625 3550);
FORCEPROP 1 LAST PART_NUMBER A36096-030
J 0
(-2625 3500);
DISPLAY 0.617021 (-2625 3500);
PAINT BLUE (-2625 3500);
FORCEPROP 1 LAST PACK_TYPE 0402V
J 0
(-2625 3450);
DISPLAY 0.617021 (-2625 3450);
PAINT SKYBLUE (-2625 3450);
FORCEPROP 1 LASTPIN (-2675 3750) $PN 1
J 0
(-2665 3730);
DISPLAY 0.617021 (-2665 3730);
PAINT ORANGE (-2665 3730);
FORCEPROP 1 LASTPIN (-2675 3550) $PN 2
J 0
(-2665 3530);
DISPLAY 0.617021 (-2665 3530);
PAINT ORANGE (-2665 3530);
FORCEPROP 0 LAST POP NOPOP
J 0
(-2625 3400);
DISPLAY 0.638298 (-2625 3400);
PAINT RED (-2625 3400);
FORCEPROP 2 LAST SEC_TYPE 0402V
J 0
(-2625 3850);
DISPLAY 1.021277 (-2625 3850);
PAINT ORANGE (-2625 3850);
DISPLAY INVISIBLE (-2625 3850);
FORCEPROP 2 LAST SEC 1
J 0
(-2625 3850);
DISPLAY 0.680851 (-2625 3850);
PAINT MONO (-2625 3850);
DISPLAY INVISIBLE (-2625 3850);
FORCEPROP 1 LAST PATH I36
J 0
(-2625 3800);
DISPLAY 0.978723 (-2625 3800);
PAINT WHITE (-2625 3800);
DISPLAY INVISIBLE (-2625 3800);
FORCEPROP 2 LAST BOM_COST HOT_SWAP
J 0
(-2575 3800);
PAINT MONO (-2575 3800);
DISPLAY INVISIBLE (-2575 3800);
FORCEPROP 2 LAST CDS_SEC 1
J 0
(-2625 3800);
PAINT ORANGE (-2625 3800);
DISPLAY INVISIBLE (-2625 3800);
FORCEPROP 2 LAST CDS_LIB dev_discrete
J 0
(-2675 3650);
PAINT ORANGE (-2675 3650);
DISPLAY INVISIBLE (-2675 3650);
FORCEPROP 0 LAST ROOM HOT_SWAP
J 0
(-2625 3725);
DISPLAY 0.978723 (-2625 3725);
PAINT GREEN (-2625 3725);
DISPLAY INVISIBLE (-2625 3725);
FORCEPROP 2 LAST CDS_LOCATION C9R12
J 0
(-2625 3750);
DISPLAY 0.617021 (-2625 3750);
PAINT AQUA (-2625 3750);
DISPLAY INVISIBLE (-2625 3750);
FORCEADD CAP_A..1
(-2300 3650);
FORCEPROP 1 LAST PART_NUMBER A36096-030
J 0
(-2250 3500);
DISPLAY 0.617021 (-2250 3500);
PAINT BLUE (-2250 3500);
FORCEPROP 1 LAST PACK_TYPE 0402V
J 0
(-2250 3450);
DISPLAY 0.617021 (-2250 3450);
PAINT SKYBLUE (-2250 3450);
FORCEPROP 1 LAST VALUE 0.1UF
J 0
(-2250 3700);
DISPLAY 0.617021 (-2250 3700);
PAINT SKYBLUE (-2250 3700);
FORCEPROP 1 LAST VOLTAGE 16V
J 0
(-2250 3650);
DISPLAY 0.617021 (-2250 3650);
PAINT SKYBLUE (-2250 3650);
FORCEPROP 1 LAST TOLERANCE 10%
J 0
(-2250 3600);
DISPLAY 0.617021 (-2250 3600);
PAINT SKYBLUE (-2250 3600);
FORCEPROP 1 LAST LOCATION C9R6
J 0
(-2250 3750);
DISPLAY 0.617021 (-2250 3750);
PAINT AQUA (-2250 3750);
FORCEPROP 1 LASTPIN (-2300 3750) $PN 1
J 0
(-2290 3730);
DISPLAY 0.617021 (-2290 3730);
PAINT ORANGE (-2290 3730);
FORCEPROP 1 LASTPIN (-2300 3550) $PN 2
J 0
(-2290 3530);
DISPLAY 0.617021 (-2290 3530);
PAINT ORANGE (-2290 3530);
FORCEPROP 1 LAST MATERIAL X7R
J 0
(-2250 3550);
DISPLAY 0.617021 (-2250 3550);
PAINT SKYBLUE (-2250 3550);
FORCEPROP 0 LAST POP NOPOP
J 0
(-2250 3400);
DISPLAY 0.638298 (-2250 3400);
PAINT RED (-2250 3400);
FORCEPROP 2 LAST SEC 1
J 0
(-2250 3850);
DISPLAY 0.680851 (-2250 3850);
PAINT MONO (-2250 3850);
DISPLAY INVISIBLE (-2250 3850);
FORCEPROP 2 LAST SEC_TYPE 0402V
J 0
(-2250 3850);
DISPLAY 1.021277 (-2250 3850);
PAINT ORANGE (-2250 3850);
DISPLAY INVISIBLE (-2250 3850);
FORCEPROP 2 LAST CDS_SEC 1
J 0
(-2250 3800);
PAINT ORANGE (-2250 3800);
DISPLAY INVISIBLE (-2250 3800);
FORCEPROP 2 LAST BOM_COST HOT_SWAP
J 0
(-2200 3800);
PAINT MONO (-2200 3800);
DISPLAY INVISIBLE (-2200 3800);
FORCEPROP 1 LAST PATH I37
J 0
(-2250 3800);
DISPLAY 0.978723 (-2250 3800);
PAINT WHITE (-2250 3800);
DISPLAY INVISIBLE (-2250 3800);
FORCEPROP 0 LAST ROOM HOT_SWAP
J 0
(-2250 3725);
DISPLAY 0.978723 (-2250 3725);
PAINT GREEN (-2250 3725);
DISPLAY INVISIBLE (-2250 3725);
FORCEPROP 2 LAST CDS_LOCATION C9R6
J 0
(-2250 3750);
DISPLAY 0.617021 (-2250 3750);
PAINT AQUA (-2250 3750);
DISPLAY INVISIBLE (-2250 3750);
FORCEPROP 2 LAST CDS_LIB dev_discrete
J 0
(-2300 3650);
PAINT ORANGE (-2300 3650);
DISPLAY INVISIBLE (-2300 3650);
FORCEADD CAP_A..1
(-1950 3650);
FORCEPROP 1 LAST VOLTAGE 16V
J 0
(-1900 3650);
DISPLAY 0.617021 (-1900 3650);
PAINT SKYBLUE (-1900 3650);
FORCEPROP 0 LAST POP NOPOP
J 0
(-1900 3400);
DISPLAY 0.638298 (-1900 3400);
PAINT RED (-1900 3400);
FORCEPROP 1 LAST PART_NUMBER A36096-030
J 0
(-1900 3500);
DISPLAY 0.617021 (-1900 3500);
PAINT BLUE (-1900 3500);
FORCEPROP 1 LAST LOCATION C1E17
J 0
(-1900 3750);
DISPLAY 0.617021 (-1900 3750);
PAINT AQUA (-1900 3750);
FORCEPROP 1 LAST VALUE 0.1UF
J 0
(-1900 3700);
DISPLAY 0.617021 (-1900 3700);
PAINT SKYBLUE (-1900 3700);
FORCEPROP 1 LAST TOLERANCE 10%
J 0
(-1900 3600);
DISPLAY 0.617021 (-1900 3600);
PAINT SKYBLUE (-1900 3600);
FORCEPROP 1 LASTPIN (-1950 3750) $PN 1
J 0
(-1940 3730);
DISPLAY 0.617021 (-1940 3730);
PAINT ORANGE (-1940 3730);
FORCEPROP 1 LAST MATERIAL X7R
J 0
(-1900 3550);
DISPLAY 0.617021 (-1900 3550);
PAINT SKYBLUE (-1900 3550);
FORCEPROP 1 LASTPIN (-1950 3550) $PN 2
J 0
(-1940 3530);
DISPLAY 0.617021 (-1940 3530);
PAINT ORANGE (-1940 3530);
FORCEPROP 1 LAST PACK_TYPE 0402V
J 0
(-1900 3450);
DISPLAY 0.617021 (-1900 3450);
PAINT SKYBLUE (-1900 3450);
FORCEPROP 2 LAST SEC 1
J 0
(-1900 3850);
DISPLAY 0.680851 (-1900 3850);
PAINT MONO (-1900 3850);
DISPLAY INVISIBLE (-1900 3850);
FORCEPROP 2 LAST SEC_TYPE 0402V
J 0
(-1900 3850);
DISPLAY 1.021277 (-1900 3850);
PAINT ORANGE (-1900 3850);
DISPLAY INVISIBLE (-1900 3850);
FORCEPROP 2 LAST CDS_SEC 1
J 0
(-1900 3800);
PAINT ORANGE (-1900 3800);
DISPLAY INVISIBLE (-1900 3800);
FORCEPROP 2 LAST BOM_COST HOT_SWAP
J 0
(-1850 3800);
PAINT MONO (-1850 3800);
DISPLAY INVISIBLE (-1850 3800);
FORCEPROP 1 LAST PATH I38
J 0
(-1900 3800);
DISPLAY 0.978723 (-1900 3800);
PAINT WHITE (-1900 3800);
DISPLAY INVISIBLE (-1900 3800);
FORCEPROP 0 LAST ROOM HOT_SWAP
J 0
(-1900 3725);
DISPLAY 0.978723 (-1900 3725);
PAINT GREEN (-1900 3725);
DISPLAY INVISIBLE (-1900 3725);
FORCEPROP 2 LAST CDS_LOCATION C1E17
J 0
(-1900 3750);
DISPLAY 0.617021 (-1900 3750);
PAINT AQUA (-1900 3750);
DISPLAY INVISIBLE (-1900 3750);
FORCEPROP 2 LAST CDS_LIB dev_discrete
J 0
(-1950 3650);
PAINT ORANGE (-1950 3650);
DISPLAY INVISIBLE (-1950 3650);
FORCEADD CAP_A..1
(-1625 3650);
FORCEPROP 0 LAST POP NOPOP
J 0
(-1575 3400);
DISPLAY 0.638298 (-1575 3400);
PAINT RED (-1575 3400);
FORCEPROP 1 LAST PART_NUMBER A36096-030
J 0
(-1575 3500);
DISPLAY 0.617021 (-1575 3500);
PAINT BLUE (-1575 3500);
FORCEPROP 1 LASTPIN (-1625 3550) $PN 2
J 0
(-1615 3530);
DISPLAY 0.617021 (-1615 3530);
PAINT ORANGE (-1615 3530);
FORCEPROP 1 LASTPIN (-1625 3750) $PN 1
J 0
(-1615 3730);
DISPLAY 0.617021 (-1615 3730);
PAINT ORANGE (-1615 3730);
FORCEPROP 1 LAST MATERIAL X7R
J 0
(-1575 3550);
DISPLAY 0.617021 (-1575 3550);
PAINT SKYBLUE (-1575 3550);
FORCEPROP 1 LAST VOLTAGE 16V
J 0
(-1575 3650);
DISPLAY 0.617021 (-1575 3650);
PAINT SKYBLUE (-1575 3650);
FORCEPROP 1 LAST TOLERANCE 10%
J 0
(-1575 3600);
DISPLAY 0.617021 (-1575 3600);
PAINT SKYBLUE (-1575 3600);
FORCEPROP 1 LAST VALUE 0.1UF
J 0
(-1575 3700);
DISPLAY 0.617021 (-1575 3700);
PAINT SKYBLUE (-1575 3700);
FORCEPROP 1 LAST LOCATION C1E16
J 0
(-1575 3750);
DISPLAY 0.617021 (-1575 3750);
PAINT AQUA (-1575 3750);
FORCEPROP 1 LAST PACK_TYPE 0402V
J 0
(-1575 3450);
DISPLAY 0.617021 (-1575 3450);
PAINT SKYBLUE (-1575 3450);
FORCEPROP 2 LAST CDS_LIB dev_discrete
J 0
(-1625 3650);
PAINT ORANGE (-1625 3650);
DISPLAY INVISIBLE (-1625 3650);
FORCEPROP 2 LAST CDS_LOCATION C1E16
J 0
(-1575 3750);
DISPLAY 0.617021 (-1575 3750);
PAINT AQUA (-1575 3750);
DISPLAY INVISIBLE (-1575 3750);
FORCEPROP 0 LAST ROOM HOT_SWAP
J 0
(-1575 3725);
DISPLAY 0.978723 (-1575 3725);
PAINT GREEN (-1575 3725);
DISPLAY INVISIBLE (-1575 3725);
FORCEPROP 2 LAST CDS_SEC 1
J 0
(-1575 3800);
PAINT ORANGE (-1575 3800);
DISPLAY INVISIBLE (-1575 3800);
FORCEPROP 2 LAST SEC 1
J 0
(-1575 3850);
DISPLAY 0.680851 (-1575 3850);
PAINT MONO (-1575 3850);
DISPLAY INVISIBLE (-1575 3850);
FORCEPROP 2 LAST SEC_TYPE 0402V
J 0
(-1575 3850);
DISPLAY 1.021277 (-1575 3850);
PAINT ORANGE (-1575 3850);
DISPLAY INVISIBLE (-1575 3850);
FORCEPROP 2 LAST BOM_COST HOT_SWAP
J 0
(-1525 3800);
PAINT MONO (-1525 3800);
DISPLAY INVISIBLE (-1525 3800);
FORCEPROP 1 LAST PATH I39
J 0
(-1575 3800);
DISPLAY 0.978723 (-1575 3800);
PAINT WHITE (-1575 3800);
DISPLAY INVISIBLE (-1575 3800);
FORCEADD P12V_PSU..1
(-1625 4025);
FORCEPROP 3 LASTPIN (-1625 3975) SIG_NAME P12V_PSU\g
J 0
(-1615 3985);
DISPLAY 0.659574 (-1615 3985);
PAINT MONO (-1615 3985);
DISPLAY INVISIBLE (-1615 3985);
FORCEPROP 1 LAST VOLTAGE 12.0
J 0
(-1670 3982);
DISPLAY 0.340426 (-1670 3982);
PAINT SKYBLUE (-1670 3982);
DISPLAY INVISIBLE (-1670 3982);
FORCEPROP 2 LAST CDS_LIB mstr_symbols
J 0
(-1625 4025);
PAINT ORANGE (-1625 4025);
DISPLAY INVISIBLE (-1625 4025);
FORCEPROP 1 LAST PATH I40
J 0
(-1575 4050);
DISPLAY 0.872340 (-1575 4050);
PAINT AQUA (-1575 4050);
DISPLAY INVISIBLE (-1575 4050);
FORCEPROP 2 LAST ROOM P2V5_LAN_AUX_VR
J 0
(-1625 4125);
DISPLAY 0.617021 (-1625 4125);
PAINT ORANGE (-1625 4125);
DISPLAY INVISIBLE (-1625 4125);
FORCEPROP 2 LAST BOM_COST NT_BASE_VRD
J 0
(-1625 4125);
DISPLAY 0.617021 (-1625 4125);
PAINT ORANGE (-1625 4125);
DISPLAY INVISIBLE (-1625 4125);
FORCEPROP 1 LAST BODY_TYPE PLUMBING
J 0
(-1670 3982);
DISPLAY 0.340426 (-1670 3982);
PAINT GREEN (-1670 3982);
DISPLAY INVISIBLE (-1670 3982);
FORCEPROP 1 LAST HDL_POWER P12V_PSU
J 1
(-1625 4075);
DISPLAY 0.872340 (-1625 4075);
PAINT GREEN (-1625 4075);
DISPLAY INVISIBLE (-1625 4075);
FORCEADD GND..1
(-6900 4525);
FORCEPROP 3 LASTPIN (-6900 4575) SIG_NAME GND\g
J 0
(-6890 4585);
DISPLAY 0.659574 (-6890 4585);
PAINT MONO (-6890 4585);
DISPLAY INVISIBLE (-6890 4585);
FORCEPROP 1 LAST SIZE 1B
J 0
(-6825 4475);
DISPLAY 0.872340 (-6825 4475);
PAINT AQUA (-6825 4475);
DISPLAY INVISIBLE (-6825 4475);
FORCEPROP 2 LAST CDS_LIB mstr_symbols
J 0
(-6900 4525);
PAINT ORANGE (-6900 4525);
DISPLAY INVISIBLE (-6900 4525);
FORCEPROP 1 LAST VOLTAGE 0.0V
J 0
(-6945 4482);
DISPLAY 0.340426 (-6945 4482);
PAINT SKYBLUE (-6945 4482);
DISPLAY INVISIBLE (-6945 4482);
FORCEPROP 1 LAST PATH I48
J 0
(-6825 4525);
DISPLAY 0.872340 (-6825 4525);
PAINT AQUA (-6825 4525);
DISPLAY INVISIBLE (-6825 4525);
FORCEPROP 1 LAST BODY_TYPE PLUMBING
J 0
(-6945 4482);
DISPLAY 0.340426 (-6945 4482);
PAINT GREEN (-6945 4482);
DISPLAY INVISIBLE (-6945 4482);
FORCEPROP 1 LAST HDL_POWER GND
J 0
(-6900 4675);
DISPLAY 0.872340 (-6900 4675);
PAINT GREEN (-6900 4675);
DISPLAY INVISIBLE (-6900 4675);
FORCEADD MTG_KEYHOLE..1
(-6475 4725);
FORCEPROP 1 LAST LOCATION TH4G1
J 0
(-6675 4925);
DISPLAY 0.617021 (-6675 4925);
PAINT AQUA (-6675 4925);
FORCEPROP 2 LASTPIN (-6725 4725) $PN 1
J 2
(-6735 4735);
DISPLAY 0.617021 (-6735 4735);
PAINT MONO (-6735 4735);
FORCEPROP 1 LAST MATERIAL EMPTY
J 0
(-6675 4875);
DISPLAY 0.617021 (-6675 4875);
PAINT RED (-6675 4875);
FORCEPROP 1 LAST PART_NUMBER NA
J 0
(-6675 4575);
DISPLAY 0.617021 (-6675 4575);
PAINT BLUE (-6675 4575);
FORCEPROP 2 LAST $SEC 1
J 0
(-6675 4975);
DISPLAY 0.680851 (-6675 4975);
PAINT MONO (-6675 4975);
DISPLAY INVISIBLE (-6675 4975);
FORCEPROP 0 LAST ROOM MOUNTING_HOLES
J 0
(-6675 4975);
DISPLAY 1.021277 (-6675 4975);
PAINT ORANGE (-6675 4975);
DISPLAY INVISIBLE (-6675 4975);
FORCEPROP 2 LAST CDS_LOCATION TH4G1
J 0
(-6675 4925);
DISPLAY 0.617021 (-6675 4925);
PAINT AQUA (-6675 4925);
DISPLAY INVISIBLE (-6675 4925);
FORCEPROP 0 LAST BOM_COST TEST_MFG
J 0
(-6675 5025);
DISPLAY 1.021277 (-6675 5025);
PAINT ORANGE (-6675 5025);
DISPLAY INVISIBLE (-6675 5025);
FORCEPROP 2 LAST CDS_SEC 1
J 0
(-6675 4975);
DISPLAY 1.021277 (-6675 4975);
PAINT ORANGE (-6675 4975);
DISPLAY INVISIBLE (-6675 4975);
FORCEPROP 1 LAST PACK_TYPE TH
J 0
(-6675 4975);
DISPLAY 0.978723 (-6675 4975);
PAINT SKYBLUE (-6675 4975);
DISPLAY INVISIBLE (-6675 4975);
FORCEPROP 2 LAST CDS_LIB mstr_misc
J 0
(-6475 4725);
PAINT ORANGE (-6475 4725);
DISPLAY INVISIBLE (-6475 4725);
FORCEPROP 1 LAST PATH I49
J 0
(-6475 4875);
DISPLAY 0.978723 (-6475 4875);
PAINT GREEN (-6475 4875);
DISPLAY INVISIBLE (-6475 4875);
FORCEADD MTG_KEYHOLE..1
(-6425 4125);
FORCEPROP 1 LAST MATERIAL EMPTY
J 0
(-6625 4275);
DISPLAY 0.617021 (-6625 4275);
PAINT RED (-6625 4275);
FORCEPROP 1 LAST PART_NUMBER NA
J 0
(-6625 3975);
DISPLAY 0.617021 (-6625 3975);
PAINT BLUE (-6625 3975);
FORCEPROP 2 LASTPIN (-6675 4125) $PN 1
J 2
(-6685 4135);
DISPLAY 0.617021 (-6685 4135);
PAINT MONO (-6685 4135);
FORCEPROP 1 LAST LOCATION TH9G1
J 0
(-6625 4325);
DISPLAY 0.617021 (-6625 4325);
PAINT AQUA (-6625 4325);
FORCEPROP 2 LAST CDS_LOCATION TH9G1
J 0
(-6625 4325);
DISPLAY 0.617021 (-6625 4325);
PAINT AQUA (-6625 4325);
DISPLAY INVISIBLE (-6625 4325);
FORCEPROP 2 LAST CDS_LIB mstr_misc
J 0
(-6425 4125);
PAINT ORANGE (-6425 4125);
DISPLAY INVISIBLE (-6425 4125);
FORCEPROP 1 LAST PATH I52
J 0
(-6425 4275);
DISPLAY 0.978723 (-6425 4275);
PAINT GREEN (-6425 4275);
DISPLAY INVISIBLE (-6425 4275);
FORCEPROP 0 LAST ROOM MOUNTING_HOLES
J 0
(-6625 4375);
DISPLAY 1.021277 (-6625 4375);
PAINT ORANGE (-6625 4375);
DISPLAY INVISIBLE (-6625 4375);
FORCEPROP 2 LAST $SEC 1
J 0
(-6625 4375);
DISPLAY 0.680851 (-6625 4375);
PAINT MONO (-6625 4375);
DISPLAY INVISIBLE (-6625 4375);
FORCEPROP 2 LAST CDS_SEC 1
J 0
(-6625 4375);
DISPLAY 1.021277 (-6625 4375);
PAINT ORANGE (-6625 4375);
DISPLAY INVISIBLE (-6625 4375);
FORCEPROP 0 LAST BOM_COST TEST_MFG
J 0
(-6625 4425);
DISPLAY 1.021277 (-6625 4425);
PAINT ORANGE (-6625 4425);
DISPLAY INVISIBLE (-6625 4425);
FORCEPROP 1 LAST PACK_TYPE TH
J 0
(-6625 4375);
DISPLAY 0.978723 (-6625 4375);
PAINT SKYBLUE (-6625 4375);
DISPLAY INVISIBLE (-6625 4375);
FORCEADD GND..1
(-6850 3925);
FORCEPROP 3 LASTPIN (-6850 3975) SIG_NAME GND\g
J 0
(-6840 3985);
DISPLAY 0.659574 (-6840 3985);
PAINT MONO (-6840 3985);
DISPLAY INVISIBLE (-6840 3985);
FORCEPROP 1 LAST VOLTAGE 0.0V
J 0
(-6895 3882);
DISPLAY 0.340426 (-6895 3882);
PAINT SKYBLUE (-6895 3882);
DISPLAY INVISIBLE (-6895 3882);
FORCEPROP 2 LAST CDS_LIB mstr_symbols
J 0
(-6850 3925);
PAINT ORANGE (-6850 3925);
DISPLAY INVISIBLE (-6850 3925);
FORCEPROP 1 LAST SIZE 1B
J 0
(-6775 3875);
DISPLAY 0.872340 (-6775 3875);
PAINT AQUA (-6775 3875);
DISPLAY INVISIBLE (-6775 3875);
FORCEPROP 1 LAST PATH I53
J 0
(-6775 3925);
DISPLAY 0.872340 (-6775 3925);
PAINT AQUA (-6775 3925);
DISPLAY INVISIBLE (-6775 3925);
FORCEPROP 1 LAST BODY_TYPE PLUMBING
J 0
(-6895 3882);
DISPLAY 0.340426 (-6895 3882);
PAINT GREEN (-6895 3882);
DISPLAY INVISIBLE (-6895 3882);
FORCEPROP 1 LAST HDL_POWER GND
J 0
(-6850 4075);
DISPLAY 0.872340 (-6850 4075);
PAINT GREEN (-6850 4075);
DISPLAY INVISIBLE (-6850 4075);
FORCEADD MTG_KEYHOLE..1
(-4600 4725);
FORCEPROP 1 LAST PART_NUMBER NA
J 0
(-4800 4575);
DISPLAY 0.617021 (-4800 4575);
PAINT BLUE (-4800 4575);
FORCEPROP 2 LASTPIN (-4850 4725) $PN 1
J 2
(-4860 4735);
DISPLAY 0.617021 (-4860 4735);
PAINT MONO (-4860 4735);
FORCEPROP 1 LAST LOCATION TH9A1
J 0
(-4775 4950);
DISPLAY 0.617021 (-4775 4950);
PAINT AQUA (-4775 4950);
FORCEPROP 1 LAST MATERIAL EMPTY
J 0
(-4800 4875);
DISPLAY 0.617021 (-4800 4875);
PAINT RED (-4800 4875);
FORCEPROP 0 LAST ROOM MOUNTING_HOLES
J 0
(-4800 4975);
DISPLAY 1.021277 (-4800 4975);
PAINT ORANGE (-4800 4975);
DISPLAY INVISIBLE (-4800 4975);
FORCEPROP 2 LAST CDS_LOCATION TH9A1
J 0
(-4775 4950);
DISPLAY 0.617021 (-4775 4950);
PAINT AQUA (-4775 4950);
DISPLAY INVISIBLE (-4775 4950);
FORCEPROP 2 LAST $SEC 1
J 0
(-4800 4975);
DISPLAY 0.680851 (-4800 4975);
PAINT MONO (-4800 4975);
DISPLAY INVISIBLE (-4800 4975);
FORCEPROP 2 LAST CDS_SEC 1
J 0
(-4800 4975);
DISPLAY 1.021277 (-4800 4975);
PAINT ORANGE (-4800 4975);
DISPLAY INVISIBLE (-4800 4975);
FORCEPROP 0 LAST BOM_COST TEST_MFG
J 0
(-4800 5025);
DISPLAY 1.021277 (-4800 5025);
PAINT ORANGE (-4800 5025);
DISPLAY INVISIBLE (-4800 5025);
FORCEPROP 1 LAST PACK_TYPE TH
J 0
(-4800 4975);
DISPLAY 0.978723 (-4800 4975);
PAINT SKYBLUE (-4800 4975);
DISPLAY INVISIBLE (-4800 4975);
FORCEPROP 2 LAST CDS_LIB mstr_misc
J 0
(-4600 4725);
PAINT ORANGE (-4600 4725);
DISPLAY INVISIBLE (-4600 4725);
FORCEPROP 1 LAST PATH I54
J 0
(-4600 4875);
DISPLAY 0.978723 (-4600 4875);
PAINT GREEN (-4600 4875);
DISPLAY INVISIBLE (-4600 4875);
FORCEADD GND..1
(-5025 4525);
FORCEPROP 3 LASTPIN (-5025 4575) SIG_NAME GND\g
J 0
(-5015 4585);
DISPLAY 0.659574 (-5015 4585);
PAINT MONO (-5015 4585);
DISPLAY INVISIBLE (-5015 4585);
FORCEPROP 1 LAST PATH I55
J 0
(-4950 4525);
DISPLAY 0.872340 (-4950 4525);
PAINT AQUA (-4950 4525);
DISPLAY INVISIBLE (-4950 4525);
FORCEPROP 2 LAST CDS_LIB mstr_symbols
J 0
(-5025 4525);
PAINT ORANGE (-5025 4525);
DISPLAY INVISIBLE (-5025 4525);
FORCEPROP 1 LAST SIZE 1B
J 0
(-4950 4475);
DISPLAY 0.872340 (-4950 4475);
PAINT AQUA (-4950 4475);
DISPLAY INVISIBLE (-4950 4475);
FORCEPROP 1 LAST VOLTAGE 0.0V
J 0
(-5070 4482);
DISPLAY 0.340426 (-5070 4482);
PAINT SKYBLUE (-5070 4482);
DISPLAY INVISIBLE (-5070 4482);
FORCEPROP 1 LAST BODY_TYPE PLUMBING
J 0
(-5070 4482);
DISPLAY 0.340426 (-5070 4482);
PAINT GREEN (-5070 4482);
DISPLAY INVISIBLE (-5070 4482);
FORCEPROP 1 LAST HDL_POWER GND
J 0
(-5025 4675);
DISPLAY 0.872340 (-5025 4675);
PAINT GREEN (-5025 4675);
DISPLAY INVISIBLE (-5025 4675);
FORCEADD MTG_KEYHOLE..1
(-5525 4725);
FORCEPROP 1 LAST PART_NUMBER NA
J 0
(-5725 4575);
DISPLAY 0.617021 (-5725 4575);
PAINT BLUE (-5725 4575);
FORCEPROP 1 LAST MATERIAL EMPTY
J 0
(-5725 4875);
DISPLAY 0.617021 (-5725 4875);
PAINT RED (-5725 4875);
FORCEPROP 1 LAST LOCATION TH1A1
J 0
(-5725 4950);
DISPLAY 0.617021 (-5725 4950);
PAINT AQUA (-5725 4950);
FORCEPROP 2 LASTPIN (-5775 4725) $PN 1
J 2
(-5785 4735);
DISPLAY 0.617021 (-5785 4735);
PAINT MONO (-5785 4735);
FORCEPROP 1 LAST PACK_TYPE TH
J 0
(-5725 4975);
DISPLAY 0.978723 (-5725 4975);
PAINT SKYBLUE (-5725 4975);
DISPLAY INVISIBLE (-5725 4975);
FORCEPROP 0 LAST BOM_COST TEST_MFG
J 0
(-5725 5025);
DISPLAY 1.021277 (-5725 5025);
PAINT ORANGE (-5725 5025);
DISPLAY INVISIBLE (-5725 5025);
FORCEPROP 2 LAST CDS_SEC 1
J 0
(-5725 4975);
DISPLAY 1.021277 (-5725 4975);
PAINT ORANGE (-5725 4975);
DISPLAY INVISIBLE (-5725 4975);
FORCEPROP 2 LAST $SEC 1
J 0
(-5725 4975);
DISPLAY 0.680851 (-5725 4975);
PAINT MONO (-5725 4975);
DISPLAY INVISIBLE (-5725 4975);
FORCEPROP 2 LAST CDS_LOCATION TH1A1
J 0
(-5725 4950);
DISPLAY 0.617021 (-5725 4950);
PAINT AQUA (-5725 4950);
DISPLAY INVISIBLE (-5725 4950);
FORCEPROP 0 LAST ROOM MOUNTING_HOLES
J 0
(-5725 4975);
DISPLAY 1.021277 (-5725 4975);
PAINT ORANGE (-5725 4975);
DISPLAY INVISIBLE (-5725 4975);
FORCEPROP 2 LAST CDS_LIB mstr_misc
J 0
(-5525 4725);
PAINT ORANGE (-5525 4725);
DISPLAY INVISIBLE (-5525 4725);
FORCEPROP 1 LAST PATH I56
J 0
(-5525 4875);
DISPLAY 0.978723 (-5525 4875);
PAINT GREEN (-5525 4875);
DISPLAY INVISIBLE (-5525 4875);
FORCEADD GND..1
(-5950 4525);
FORCEPROP 3 LASTPIN (-5950 4575) SIG_NAME GND\g
J 0
(-5940 4585);
DISPLAY 0.659574 (-5940 4585);
PAINT MONO (-5940 4585);
DISPLAY INVISIBLE (-5940 4585);
FORCEPROP 2 LAST CDS_LIB mstr_symbols
J 0
(-5950 4525);
PAINT ORANGE (-5950 4525);
DISPLAY INVISIBLE (-5950 4525);
FORCEPROP 1 LAST VOLTAGE 0.0V
J 0
(-5995 4482);
DISPLAY 0.340426 (-5995 4482);
PAINT SKYBLUE (-5995 4482);
DISPLAY INVISIBLE (-5995 4482);
FORCEPROP 1 LAST PATH I57
J 0
(-5875 4525);
DISPLAY 0.872340 (-5875 4525);
PAINT AQUA (-5875 4525);
DISPLAY INVISIBLE (-5875 4525);
FORCEPROP 1 LAST SIZE 1B
J 0
(-5875 4475);
DISPLAY 0.872340 (-5875 4475);
PAINT AQUA (-5875 4475);
DISPLAY INVISIBLE (-5875 4475);
FORCEPROP 1 LAST BODY_TYPE PLUMBING
J 0
(-5995 4482);
DISPLAY 0.340426 (-5995 4482);
PAINT GREEN (-5995 4482);
DISPLAY INVISIBLE (-5995 4482);
FORCEPROP 1 LAST HDL_POWER GND
J 0
(-5950 4675);
DISPLAY 0.872340 (-5950 4675);
PAINT GREEN (-5950 4675);
DISPLAY INVISIBLE (-5950 4675);
FORCEADD MTG_KEYHOLE..1
(-7350 4125);
FORCEPROP 1 LAST MATERIAL EMPTY
J 0
(-7550 4275);
DISPLAY 0.617021 (-7550 4275);
PAINT RED (-7550 4275);
FORCEPROP 1 LAST PART_NUMBER NA
J 0
(-7550 3975);
DISPLAY 0.617021 (-7550 3975);
PAINT BLUE (-7550 3975);
FORCEPROP 2 LASTPIN (-7600 4125) $PN 1
J 2
(-7610 4135);
DISPLAY 0.617021 (-7610 4135);
PAINT MONO (-7610 4135);
FORCEPROP 1 LAST LOCATION TH4A1
J 0
(-7550 4325);
DISPLAY 0.617021 (-7550 4325);
PAINT AQUA (-7550 4325);
FORCEPROP 0 LAST ROOM MOUNTING_HOLES
J 0
(-7550 4375);
DISPLAY 1.021277 (-7550 4375);
PAINT ORANGE (-7550 4375);
DISPLAY INVISIBLE (-7550 4375);
FORCEPROP 2 LAST CDS_LOCATION TH4A1
J 0
(-7550 4325);
DISPLAY 0.617021 (-7550 4325);
PAINT AQUA (-7550 4325);
DISPLAY INVISIBLE (-7550 4325);
FORCEPROP 2 LAST $SEC 1
J 0
(-7550 4375);
DISPLAY 0.680851 (-7550 4375);
PAINT MONO (-7550 4375);
DISPLAY INVISIBLE (-7550 4375);
FORCEPROP 2 LAST CDS_SEC 1
J 0
(-7550 4375);
DISPLAY 1.021277 (-7550 4375);
PAINT ORANGE (-7550 4375);
DISPLAY INVISIBLE (-7550 4375);
FORCEPROP 0 LAST BOM_COST TEST_MFG
J 0
(-7550 4425);
DISPLAY 1.021277 (-7550 4425);
PAINT ORANGE (-7550 4425);
DISPLAY INVISIBLE (-7550 4425);
FORCEPROP 1 LAST PACK_TYPE TH
J 0
(-7550 4375);
DISPLAY 0.978723 (-7550 4375);
PAINT SKYBLUE (-7550 4375);
DISPLAY INVISIBLE (-7550 4375);
FORCEPROP 2 LAST CDS_LIB mstr_misc
J 0
(-7350 4125);
PAINT ORANGE (-7350 4125);
DISPLAY INVISIBLE (-7350 4125);
FORCEPROP 1 LAST PATH I62
J 0
(-7350 4275);
DISPLAY 0.978723 (-7350 4275);
PAINT GREEN (-7350 4275);
DISPLAY INVISIBLE (-7350 4275);
FORCEADD GND..1
(-7775 3925);
FORCEPROP 3 LASTPIN (-7775 3975) SIG_NAME GND\g
J 0
(-7765 3985);
DISPLAY 0.659574 (-7765 3985);
PAINT MONO (-7765 3985);
DISPLAY INVISIBLE (-7765 3985);
FORCEPROP 1 LAST PATH I63
J 0
(-7700 3925);
DISPLAY 0.872340 (-7700 3925);
PAINT AQUA (-7700 3925);
DISPLAY INVISIBLE (-7700 3925);
FORCEPROP 1 LAST SIZE 1B
J 0
(-7700 3875);
DISPLAY 0.872340 (-7700 3875);
PAINT AQUA (-7700 3875);
DISPLAY INVISIBLE (-7700 3875);
FORCEPROP 2 LAST CDS_LIB mstr_symbols
J 0
(-7775 3925);
PAINT ORANGE (-7775 3925);
DISPLAY INVISIBLE (-7775 3925);
FORCEPROP 1 LAST VOLTAGE 0.0V
J 0
(-7820 3882);
DISPLAY 0.340426 (-7820 3882);
PAINT SKYBLUE (-7820 3882);
DISPLAY INVISIBLE (-7820 3882);
FORCEPROP 1 LAST BODY_TYPE PLUMBING
J 0
(-7820 3882);
DISPLAY 0.340426 (-7820 3882);
PAINT GREEN (-7820 3882);
DISPLAY INVISIBLE (-7820 3882);
FORCEPROP 1 LAST HDL_POWER GND
J 0
(-7775 4075);
DISPLAY 0.872340 (-7775 4075);
PAINT GREEN (-7775 4075);
DISPLAY INVISIBLE (-7775 4075);
FORCEADD GND..1
(-5950 3950);
FORCEPROP 3 LASTPIN (-5950 4000) SIG_NAME GND\g
J 0
(-5940 4010);
DISPLAY 0.659574 (-5940 4010);
PAINT MONO (-5940 4010);
DISPLAY INVISIBLE (-5940 4010);
FORCEPROP 1 LAST VOLTAGE 0.0V
J 0
(-5995 3907);
DISPLAY 0.340426 (-5995 3907);
PAINT SKYBLUE (-5995 3907);
DISPLAY INVISIBLE (-5995 3907);
FORCEPROP 1 LAST SIZE 1B
J 0
(-5875 3900);
DISPLAY 0.872340 (-5875 3900);
PAINT AQUA (-5875 3900);
DISPLAY INVISIBLE (-5875 3900);
FORCEPROP 2 LAST CDS_LIB mstr_symbols
J 0
(-5950 3950);
PAINT ORANGE (-5950 3950);
DISPLAY INVISIBLE (-5950 3950);
FORCEPROP 1 LAST PATH I64
J 0
(-5875 3950);
DISPLAY 0.872340 (-5875 3950);
PAINT AQUA (-5875 3950);
DISPLAY INVISIBLE (-5875 3950);
FORCEPROP 1 LAST BODY_TYPE PLUMBING
J 0
(-5995 3907);
DISPLAY 0.340426 (-5995 3907);
PAINT GREEN (-5995 3907);
DISPLAY INVISIBLE (-5995 3907);
FORCEPROP 1 LAST HDL_POWER GND
J 0
(-5950 4100);
DISPLAY 0.872340 (-5950 4100);
PAINT GREEN (-5950 4100);
DISPLAY INVISIBLE (-5950 4100);
FORCEADD MTG_KEYHOLE..1
(-5525 4150);
FORCEPROP 1 LAST MATERIAL EMPTY
J 0
(-5725 4300);
DISPLAY 0.617021 (-5725 4300);
PAINT RED (-5725 4300);
FORCEPROP 1 LAST PART_NUMBER NA
J 0
(-5725 4000);
DISPLAY 0.617021 (-5725 4000);
PAINT BLUE (-5725 4000);
FORCEPROP 2 LASTPIN (-5775 4150) $PN 1
J 2
(-5785 4160);
DISPLAY 0.617021 (-5785 4160);
PAINT MONO (-5785 4160);
FORCEPROP 1 LAST LOCATION TH7A1
J 0
(-5725 4350);
DISPLAY 0.617021 (-5725 4350);
PAINT AQUA (-5725 4350);
FORCEPROP 1 LAST PACK_TYPE TH
J 0
(-5725 4400);
DISPLAY 0.978723 (-5725 4400);
PAINT SKYBLUE (-5725 4400);
DISPLAY INVISIBLE (-5725 4400);
FORCEPROP 0 LAST BOM_COST TEST_MFG
J 0
(-5725 4450);
DISPLAY 1.021277 (-5725 4450);
PAINT ORANGE (-5725 4450);
DISPLAY INVISIBLE (-5725 4450);
FORCEPROP 2 LAST CDS_SEC 1
J 0
(-5725 4400);
DISPLAY 1.021277 (-5725 4400);
PAINT ORANGE (-5725 4400);
DISPLAY INVISIBLE (-5725 4400);
FORCEPROP 2 LAST $SEC 1
J 0
(-5725 4400);
DISPLAY 0.680851 (-5725 4400);
PAINT MONO (-5725 4400);
DISPLAY INVISIBLE (-5725 4400);
FORCEPROP 2 LAST CDS_LOCATION TH7A1
J 0
(-5725 4350);
DISPLAY 0.617021 (-5725 4350);
PAINT AQUA (-5725 4350);
DISPLAY INVISIBLE (-5725 4350);
FORCEPROP 0 LAST ROOM MOUNTING_HOLES
J 0
(-5725 4400);
DISPLAY 1.021277 (-5725 4400);
PAINT ORANGE (-5725 4400);
DISPLAY INVISIBLE (-5725 4400);
FORCEPROP 2 LAST CDS_LIB mstr_misc
J 0
(-5525 4150);
PAINT ORANGE (-5525 4150);
DISPLAY INVISIBLE (-5525 4150);
FORCEPROP 1 LAST PATH I65
J 0
(-5525 4300);
DISPLAY 0.978723 (-5525 4300);
PAINT GREEN (-5525 4300);
DISPLAY INVISIBLE (-5525 4300);
FORCEADD GND..1
(-5025 3950);
FORCEPROP 3 LASTPIN (-5025 4000) SIG_NAME GND\g
J 0
(-5015 4010);
DISPLAY 0.659574 (-5015 4010);
PAINT MONO (-5015 4010);
DISPLAY INVISIBLE (-5015 4010);
FORCEPROP 1 LAST PATH I66
J 0
(-4950 3950);
DISPLAY 0.872340 (-4950 3950);
PAINT AQUA (-4950 3950);
DISPLAY INVISIBLE (-4950 3950);
FORCEPROP 2 LAST CDS_LIB mstr_symbols
J 0
(-5025 3950);
PAINT ORANGE (-5025 3950);
DISPLAY INVISIBLE (-5025 3950);
FORCEPROP 1 LAST SIZE 1B
J 0
(-4950 3900);
DISPLAY 0.872340 (-4950 3900);
PAINT AQUA (-4950 3900);
DISPLAY INVISIBLE (-4950 3900);
FORCEPROP 1 LAST VOLTAGE 0.0V
J 0
(-5070 3907);
DISPLAY 0.340426 (-5070 3907);
PAINT SKYBLUE (-5070 3907);
DISPLAY INVISIBLE (-5070 3907);
FORCEPROP 1 LAST BODY_TYPE PLUMBING
J 0
(-5070 3907);
DISPLAY 0.340426 (-5070 3907);
PAINT GREEN (-5070 3907);
DISPLAY INVISIBLE (-5070 3907);
FORCEPROP 1 LAST HDL_POWER GND
J 0
(-5025 4100);
DISPLAY 0.872340 (-5025 4100);
PAINT GREEN (-5025 4100);
DISPLAY INVISIBLE (-5025 4100);
FORCEADD MTG_KEYHOLE..1
(-4600 4150);
FORCEPROP 1 LAST PART_NUMBER NA
J 0
(-4800 4000);
DISPLAY 0.617021 (-4800 4000);
PAINT BLUE (-4800 4000);
FORCEPROP 2 LASTPIN (-4850 4150) $PN 1
J 2
(-4860 4160);
DISPLAY 0.617021 (-4860 4160);
PAINT MONO (-4860 4160);
FORCEPROP 1 LAST MATERIAL EMPTY
J 0
(-4800 4300);
DISPLAY 0.617021 (-4800 4300);
PAINT RED (-4800 4300);
FORCEPROP 1 LAST LOCATION TH7G1
J 0
(-4800 4350);
DISPLAY 0.617021 (-4800 4350);
PAINT AQUA (-4800 4350);
FORCEPROP 2 LAST CDS_LOCATION TH7G1
J 0
(-4800 4350);
DISPLAY 0.617021 (-4800 4350);
PAINT AQUA (-4800 4350);
DISPLAY INVISIBLE (-4800 4350);
FORCEPROP 0 LAST ROOM MOUNTING_HOLES
J 0
(-4800 4400);
DISPLAY 1.021277 (-4800 4400);
PAINT ORANGE (-4800 4400);
DISPLAY INVISIBLE (-4800 4400);
FORCEPROP 2 LAST $SEC 1
J 0
(-4800 4400);
DISPLAY 0.680851 (-4800 4400);
PAINT MONO (-4800 4400);
DISPLAY INVISIBLE (-4800 4400);
FORCEPROP 2 LAST CDS_SEC 1
J 0
(-4800 4400);
DISPLAY 1.021277 (-4800 4400);
PAINT ORANGE (-4800 4400);
DISPLAY INVISIBLE (-4800 4400);
FORCEPROP 0 LAST BOM_COST TEST_MFG
J 0
(-4800 4450);
DISPLAY 1.021277 (-4800 4450);
PAINT ORANGE (-4800 4450);
DISPLAY INVISIBLE (-4800 4450);
FORCEPROP 1 LAST PACK_TYPE TH
J 0
(-4800 4400);
DISPLAY 0.978723 (-4800 4400);
PAINT SKYBLUE (-4800 4400);
DISPLAY INVISIBLE (-4800 4400);
FORCEPROP 2 LAST CDS_LIB mstr_misc
J 0
(-4600 4150);
PAINT ORANGE (-4600 4150);
DISPLAY INVISIBLE (-4600 4150);
FORCEPROP 1 LAST PATH I67
J 0
(-4600 4300);
DISPLAY 0.978723 (-4600 4300);
PAINT GREEN (-4600 4300);
DISPLAY INVISIBLE (-4600 4300);
FORCEADD P12V_PSU..1
(-550 2750);
FORCEPROP 3 LASTPIN (-550 2700) SIG_NAME P12V_PSU\g
J 0
(-540 2710);
DISPLAY 0.659574 (-540 2710);
PAINT MONO (-540 2710);
DISPLAY INVISIBLE (-540 2710);
FORCEPROP 1 LAST PATH I77
J 0
(-500 2775);
DISPLAY 0.872340 (-500 2775);
PAINT AQUA (-500 2775);
DISPLAY INVISIBLE (-500 2775);
FORCEPROP 1 LAST VOLTAGE 12.0
J 0
(-595 2707);
DISPLAY 0.340426 (-595 2707);
PAINT SKYBLUE (-595 2707);
DISPLAY INVISIBLE (-595 2707);
FORCEPROP 2 LAST BOM_COST NT_BASE_VRD
J 0
(-550 2850);
DISPLAY 0.617021 (-550 2850);
PAINT ORANGE (-550 2850);
DISPLAY INVISIBLE (-550 2850);
FORCEPROP 2 LAST CDS_LIB mstr_symbols
J 0
(-550 2750);
PAINT ORANGE (-550 2750);
DISPLAY INVISIBLE (-550 2750);
FORCEPROP 2 LAST ROOM P2V5_LAN_AUX_VR
J 0
(-550 2850);
DISPLAY 0.617021 (-550 2850);
PAINT ORANGE (-550 2850);
DISPLAY INVISIBLE (-550 2850);
FORCEPROP 1 LAST BODY_TYPE PLUMBING
J 0
(-595 2707);
DISPLAY 0.340426 (-595 2707);
PAINT GREEN (-595 2707);
DISPLAY INVISIBLE (-595 2707);
FORCEPROP 1 LAST HDL_POWER P12V_PSU
J 1
(-550 2800);
DISPLAY 0.872340 (-550 2800);
PAINT GREEN (-550 2800);
DISPLAY INVISIBLE (-550 2800);
FORCEADD GND..1
(-650 1900);
FORCEPROP 3 LASTPIN (-650 1950) SIG_NAME GND\g
J 0
(-640 1960);
DISPLAY 0.659574 (-640 1960);
PAINT MONO (-640 1960);
DISPLAY INVISIBLE (-640 1960);
FORCEPROP 1 LAST VOLTAGE 0.0V
J 0
(-695 1857);
DISPLAY 0.340426 (-695 1857);
PAINT SKYBLUE (-695 1857);
DISPLAY INVISIBLE (-695 1857);
FORCEPROP 1 LAST SIZE 1B
J 0
(-575 1850);
DISPLAY 0.872340 (-575 1850);
PAINT AQUA (-575 1850);
DISPLAY INVISIBLE (-575 1850);
FORCEPROP 2 LAST CDS_LIB mstr_symbols
J 0
(-650 1900);
PAINT ORANGE (-650 1900);
DISPLAY INVISIBLE (-650 1900);
FORCEPROP 1 LAST PATH I79
J 0
(-575 1900);
DISPLAY 0.872340 (-575 1900);
PAINT AQUA (-575 1900);
DISPLAY INVISIBLE (-575 1900);
FORCEPROP 1 LAST BODY_TYPE PLUMBING
J 0
(-695 1857);
DISPLAY 0.340426 (-695 1857);
PAINT GREEN (-695 1857);
DISPLAY INVISIBLE (-695 1857);
FORCEPROP 1 LAST HDL_POWER GND
J 0
(-650 2050);
DISPLAY 0.872340 (-650 2050);
PAINT GREEN (-650 2050);
DISPLAY INVISIBLE (-650 2050);
FORCEADD P12V_PSU..1
(-1900 2750);
FORCEPROP 3 LASTPIN (-1900 2700) SIG_NAME P12V_PSU\g
J 0
(-1890 2710);
DISPLAY 0.659574 (-1890 2710);
PAINT MONO (-1890 2710);
DISPLAY INVISIBLE (-1890 2710);
FORCEPROP 1 LAST VOLTAGE 12.0
J 0
(-1945 2707);
DISPLAY 0.340426 (-1945 2707);
PAINT SKYBLUE (-1945 2707);
DISPLAY INVISIBLE (-1945 2707);
FORCEPROP 2 LAST CDS_LIB mstr_symbols
J 0
(-1900 2750);
PAINT ORANGE (-1900 2750);
DISPLAY INVISIBLE (-1900 2750);
FORCEPROP 2 LAST BOM_COST NT_BASE_VRD
J 0
(-1900 2850);
DISPLAY 0.617021 (-1900 2850);
PAINT ORANGE (-1900 2850);
DISPLAY INVISIBLE (-1900 2850);
FORCEPROP 1 LAST PATH I80
J 0
(-1850 2775);
DISPLAY 0.872340 (-1850 2775);
PAINT AQUA (-1850 2775);
DISPLAY INVISIBLE (-1850 2775);
FORCEPROP 2 LAST ROOM P2V5_LAN_AUX_VR
J 0
(-1900 2850);
DISPLAY 0.617021 (-1900 2850);
PAINT ORANGE (-1900 2850);
DISPLAY INVISIBLE (-1900 2850);
FORCEPROP 1 LAST BODY_TYPE PLUMBING
J 0
(-1945 2707);
DISPLAY 0.340426 (-1945 2707);
PAINT GREEN (-1945 2707);
DISPLAY INVISIBLE (-1945 2707);
FORCEPROP 1 LAST HDL_POWER P12V_PSU
J 1
(-1900 2800);
DISPLAY 0.872340 (-1900 2800);
PAINT GREEN (-1900 2800);
DISPLAY INVISIBLE (-1900 2800);
FORCEADD GND..1
(-1850 1900);
FORCEPROP 3 LASTPIN (-1850 1950) SIG_NAME GND\g
J 0
(-1840 1960);
DISPLAY 0.659574 (-1840 1960);
PAINT MONO (-1840 1960);
DISPLAY INVISIBLE (-1840 1960);
FORCEPROP 1 LAST PATH I81
J 0
(-1775 1900);
DISPLAY 0.872340 (-1775 1900);
PAINT AQUA (-1775 1900);
DISPLAY INVISIBLE (-1775 1900);
FORCEPROP 1 LAST VOLTAGE 0.0V
J 0
(-1895 1857);
DISPLAY 0.340426 (-1895 1857);
PAINT SKYBLUE (-1895 1857);
DISPLAY INVISIBLE (-1895 1857);
FORCEPROP 2 LAST CDS_LIB mstr_symbols
J 0
(-1850 1900);
PAINT ORANGE (-1850 1900);
DISPLAY INVISIBLE (-1850 1900);
FORCEPROP 1 LAST SIZE 1B
J 0
(-1775 1850);
DISPLAY 0.872340 (-1775 1850);
PAINT AQUA (-1775 1850);
DISPLAY INVISIBLE (-1775 1850);
FORCEPROP 1 LAST BODY_TYPE PLUMBING
J 0
(-1895 1857);
DISPLAY 0.340426 (-1895 1857);
PAINT GREEN (-1895 1857);
DISPLAY INVISIBLE (-1895 1857);
FORCEPROP 1 LAST HDL_POWER GND
J 0
(-1850 2050);
DISPLAY 0.872340 (-1850 2050);
PAINT GREEN (-1850 2050);
DISPLAY INVISIBLE (-1850 2050);
FORCEADD CAPP..1
(-7175 2950);
FORCEPROP 1 LASTPIN (-7175 3050) $PN 1
J 0
(-7165 3035);
DISPLAY 0.617021 (-7165 3035);
PAINT ORANGE (-7165 3035);
FORCEPROP 1 LASTPIN (-7175 2850) $PN 2
J 0
(-7165 2835);
DISPLAY 0.617021 (-7165 2835);
PAINT ORANGE (-7165 2835);
FORCEPROP 1 LAST MATERIAL ALUM
J 0
(-7125 2850);
DISPLAY 0.617021 (-7125 2850);
PAINT SKYBLUE (-7125 2850);
FORCEPROP 1 LAST VOLTAGE 16V
J 0
(-7125 2900);
DISPLAY 0.617021 (-7125 2900);
PAINT SKYBLUE (-7125 2900);
FORCEPROP 1 LAST TOLERANCE 20%
J 0
(-7125 2950);
DISPLAY 0.617021 (-7125 2950);
PAINT SKYBLUE (-7125 2950);
FORCEPROP 1 LAST VALUE 470UF
J 0
(-7125 3000);
DISPLAY 0.617021 (-7125 3000);
PAINT SKYBLUE (-7125 3000);
FORCEPROP 1 LAST PART_NUMBER A93539-036
J 0
(-7125 2750);
DISPLAY 0.617021 (-7125 2750);
PAINT BLUE (-7125 2750);
FORCEPROP 1 LAST LOCATION C4F6
J 0
(-7125 3050);
DISPLAY 0.617021 (-7125 3050);
PAINT AQUA (-7125 3050);
FORCEPROP 1 LAST PACK_TYPE 4040LF
J 0
(-7125 2800);
DISPLAY 0.617021 (-7125 2800);
PAINT SKYBLUE (-7125 2800);
FORCEPROP 2 LAST CDS_LIB mstr_discrete
J 0
(-7175 2950);
PAINT MONO (-7175 2950);
DISPLAY INVISIBLE (-7175 2950);
FORCEPROP 2 LAST CDS_LOCATION C4F6
J 0
(-7125 3050);
DISPLAY 0.617021 (-7125 3050);
PAINT AQUA (-7125 3050);
DISPLAY INVISIBLE (-7125 3050);
FORCEPROP 2 LAST CDS_SEC 1
J 0
(-7125 3150);
PAINT MONO (-7125 3150);
DISPLAY INVISIBLE (-7125 3150);
FORCEPROP 2 LAST $SEC 1
J 0
(-7125 3150);
PAINT MONO (-7125 3150);
DISPLAY INVISIBLE (-7125 3150);
FORCEPROP 1 LAST PATH I82
J 0
(-7125 3100);
DISPLAY 0.978723 (-7125 3100);
PAINT ORANGE (-7125 3100);
DISPLAY INVISIBLE (-7125 3100);
FORCEADD CAPP..1
(-6675 2950);
FORCEPROP 1 LASTPIN (-6675 3050) $PN 1
J 0
(-6665 3035);
DISPLAY 0.617021 (-6665 3035);
PAINT ORANGE (-6665 3035);
FORCEPROP 1 LASTPIN (-6675 2850) $PN 2
J 0
(-6665 2835);
DISPLAY 0.617021 (-6665 2835);
PAINT ORANGE (-6665 2835);
FORCEPROP 1 LAST MATERIAL ALUM
J 0
(-6625 2850);
DISPLAY 0.617021 (-6625 2850);
PAINT SKYBLUE (-6625 2850);
FORCEPROP 1 LAST VOLTAGE 16V
J 0
(-6625 2900);
DISPLAY 0.617021 (-6625 2900);
PAINT SKYBLUE (-6625 2900);
FORCEPROP 1 LAST PACK_TYPE 4040LF
J 0
(-6625 2800);
DISPLAY 0.617021 (-6625 2800);
PAINT SKYBLUE (-6625 2800);
FORCEPROP 1 LAST TOLERANCE 20%
J 0
(-6625 2950);
DISPLAY 0.617021 (-6625 2950);
PAINT SKYBLUE (-6625 2950);
FORCEPROP 1 LAST VALUE 470UF
J 0
(-6625 3000);
DISPLAY 0.617021 (-6625 3000);
PAINT SKYBLUE (-6625 3000);
FORCEPROP 1 LAST PART_NUMBER A93539-036
J 0
(-6625 2750);
DISPLAY 0.617021 (-6625 2750);
PAINT BLUE (-6625 2750);
FORCEPROP 1 LAST LOCATION C4B13
J 0
(-6625 3050);
DISPLAY 0.617021 (-6625 3050);
PAINT AQUA (-6625 3050);
FORCEPROP 2 LAST CDS_LIB mstr_discrete
J 0
(-6675 2950);
PAINT MONO (-6675 2950);
DISPLAY INVISIBLE (-6675 2950);
FORCEPROP 2 LAST CDS_LOCATION C4B13
J 0
(-6625 3050);
DISPLAY 0.617021 (-6625 3050);
PAINT AQUA (-6625 3050);
DISPLAY INVISIBLE (-6625 3050);
FORCEPROP 2 LAST CDS_SEC 1
J 0
(-6625 3150);
PAINT MONO (-6625 3150);
DISPLAY INVISIBLE (-6625 3150);
FORCEPROP 2 LAST $SEC 1
J 0
(-6625 3150);
PAINT MONO (-6625 3150);
DISPLAY INVISIBLE (-6625 3150);
FORCEPROP 1 LAST PATH I83
J 0
(-6625 3100);
DISPLAY 0.978723 (-6625 3100);
PAINT ORANGE (-6625 3100);
DISPLAY INVISIBLE (-6625 3100);
FORCEADD CAPP..1
(-6150 2925);
FORCEPROP 1 LASTPIN (-6150 3025) $PN 1
J 0
(-6140 3010);
DISPLAY 0.617021 (-6140 3010);
PAINT ORANGE (-6140 3010);
FORCEPROP 1 LASTPIN (-6150 2825) $PN 2
J 0
(-6140 2810);
DISPLAY 0.617021 (-6140 2810);
PAINT ORANGE (-6140 2810);
FORCEPROP 1 LAST VOLTAGE 16V
J 0
(-6100 2875);
DISPLAY 0.617021 (-6100 2875);
PAINT SKYBLUE (-6100 2875);
FORCEPROP 1 LAST PACK_TYPE 4040LF
J 0
(-6100 2775);
DISPLAY 0.617021 (-6100 2775);
PAINT SKYBLUE (-6100 2775);
FORCEPROP 1 LAST TOLERANCE 20%
J 0
(-6100 2925);
DISPLAY 0.617021 (-6100 2925);
PAINT SKYBLUE (-6100 2925);
FORCEPROP 1 LAST VALUE 470UF
J 0
(-6100 2975);
DISPLAY 0.617021 (-6100 2975);
PAINT SKYBLUE (-6100 2975);
FORCEPROP 1 LAST LOCATION C1B14
J 0
(-6100 3025);
DISPLAY 0.617021 (-6100 3025);
PAINT AQUA (-6100 3025);
FORCEPROP 1 LAST PART_NUMBER A93539-036
J 0
(-6100 2725);
DISPLAY 0.617021 (-6100 2725);
PAINT BLUE (-6100 2725);
FORCEPROP 1 LAST MATERIAL ALUM
J 0
(-6100 2825);
DISPLAY 0.617021 (-6100 2825);
PAINT SKYBLUE (-6100 2825);
FORCEPROP 2 LAST CDS_LIB mstr_discrete
J 0
(-6150 2925);
PAINT MONO (-6150 2925);
DISPLAY INVISIBLE (-6150 2925);
FORCEPROP 2 LAST CDS_LOCATION C1B14
J 0
(-6100 3025);
DISPLAY 0.617021 (-6100 3025);
PAINT AQUA (-6100 3025);
DISPLAY INVISIBLE (-6100 3025);
FORCEPROP 2 LAST CDS_SEC 1
J 0
(-6100 3125);
PAINT MONO (-6100 3125);
DISPLAY INVISIBLE (-6100 3125);
FORCEPROP 2 LAST $SEC 1
J 0
(-6100 3125);
PAINT MONO (-6100 3125);
DISPLAY INVISIBLE (-6100 3125);
FORCEPROP 1 LAST PATH I84
J 0
(-6100 3075);
DISPLAY 0.978723 (-6100 3075);
PAINT ORANGE (-6100 3075);
DISPLAY INVISIBLE (-6100 3075);
FORCEADD CAPP..1
(-5650 2900);
FORCEPROP 1 LAST VOLTAGE 16V
J 0
(-5600 2850);
DISPLAY 0.617021 (-5600 2850);
PAINT SKYBLUE (-5600 2850);
FORCEPROP 1 LASTPIN (-5650 3000) $PN 1
J 0
(-5640 2985);
DISPLAY 0.617021 (-5640 2985);
PAINT ORANGE (-5640 2985);
FORCEPROP 1 LASTPIN (-5650 2800) $PN 2
J 0
(-5640 2785);
DISPLAY 0.617021 (-5640 2785);
PAINT ORANGE (-5640 2785);
FORCEPROP 1 LAST LOCATION C1F7
J 0
(-5600 3000);
DISPLAY 0.617021 (-5600 3000);
PAINT AQUA (-5600 3000);
FORCEPROP 1 LAST PART_NUMBER A93539-036
J 0
(-5600 2700);
DISPLAY 0.617021 (-5600 2700);
PAINT BLUE (-5600 2700);
FORCEPROP 1 LAST VALUE 470UF
J 0
(-5600 2950);
DISPLAY 0.617021 (-5600 2950);
PAINT SKYBLUE (-5600 2950);
FORCEPROP 1 LAST TOLERANCE 20%
J 0
(-5600 2900);
DISPLAY 0.617021 (-5600 2900);
PAINT SKYBLUE (-5600 2900);
FORCEPROP 1 LAST PACK_TYPE 4040LF
J 0
(-5600 2750);
DISPLAY 0.617021 (-5600 2750);
PAINT SKYBLUE (-5600 2750);
FORCEPROP 1 LAST MATERIAL ALUM
J 0
(-5600 2800);
DISPLAY 0.617021 (-5600 2800);
PAINT SKYBLUE (-5600 2800);
FORCEPROP 2 LAST CDS_LIB mstr_discrete
J 0
(-5650 2900);
PAINT MONO (-5650 2900);
DISPLAY INVISIBLE (-5650 2900);
FORCEPROP 2 LAST CDS_LOCATION C1F7
J 0
(-5600 3000);
DISPLAY 0.617021 (-5600 3000);
PAINT AQUA (-5600 3000);
DISPLAY INVISIBLE (-5600 3000);
FORCEPROP 1 LAST PATH I85
J 0
(-5600 3050);
DISPLAY 0.978723 (-5600 3050);
PAINT ORANGE (-5600 3050);
DISPLAY INVISIBLE (-5600 3050);
FORCEPROP 2 LAST $SEC 1
J 0
(-5600 3100);
PAINT MONO (-5600 3100);
DISPLAY INVISIBLE (-5600 3100);
FORCEPROP 2 LAST CDS_SEC 1
J 0
(-5600 3100);
PAINT MONO (-5600 3100);
DISPLAY INVISIBLE (-5600 3100);
FORCEADD P12V_STBY..1
(-6250 3375);
FORCEPROP 3 LASTPIN (-6250 3325) SIG_NAME P12V_STBY\g
J 0
(-6240 3335);
DISPLAY 0.659574 (-6240 3335);
PAINT MONO (-6240 3335);
DISPLAY INVISIBLE (-6240 3335);
FORCEPROP 1 LAST PATH I92
J 0
(-6205 3377);
DISPLAY 0.340426 (-6205 3377);
PAINT GREEN (-6205 3377);
DISPLAY INVISIBLE (-6205 3377);
FORCEPROP 1 LAST SIZE 1B
J 0
(-6205 3397);
DISPLAY 0.340426 (-6205 3397);
PAINT GREEN (-6205 3397);
DISPLAY INVISIBLE (-6205 3397);
FORCEPROP 2 LAST CDS_LIB mstr_symbols
J 0
(-6250 3375);
PAINT MONO (-6250 3375);
DISPLAY INVISIBLE (-6250 3375);
FORCEPROP 1 LAST VOLTAGE 12.0V
J 0
(-6295 3332);
DISPLAY 0.340426 (-6295 3332);
PAINT SKYBLUE (-6295 3332);
DISPLAY INVISIBLE (-6295 3332);
FORCEPROP 1 LAST BODY_TYPE PLUMBING
J 0
(-6295 3332);
DISPLAY 0.340426 (-6295 3332);
PAINT GREEN (-6295 3332);
DISPLAY INVISIBLE (-6295 3332);
FORCEPROP 1 LAST HDL_POWER P12V_STBY
J 0
(-6550 3250);
DISPLAY 0.872340 (-6550 3250);
PAINT ORANGE (-6550 3250);
DISPLAY INVISIBLE (-6550 3250);
FORCEADD P12V_STBY..1
(-6400 1150);
FORCEPROP 3 LASTPIN (-6400 1100) SIG_NAME P12V_STBY\g
J 0
(-6390 1110);
DISPLAY 0.659574 (-6390 1110);
PAINT MONO (-6390 1110);
DISPLAY INVISIBLE (-6390 1110);
FORCEPROP 1 LAST VOLTAGE 12.0V
J 0
(-6445 1107);
DISPLAY 0.340426 (-6445 1107);
PAINT SKYBLUE (-6445 1107);
DISPLAY INVISIBLE (-6445 1107);
FORCEPROP 2 LAST CDS_LIB mstr_symbols
J 0
(-6400 1150);
PAINT MONO (-6400 1150);
DISPLAY INVISIBLE (-6400 1150);
FORCEPROP 1 LAST SIZE 1B
J 0
(-6355 1172);
DISPLAY 0.340426 (-6355 1172);
PAINT GREEN (-6355 1172);
DISPLAY INVISIBLE (-6355 1172);
FORCEPROP 1 LAST PATH I93
J 0
(-6355 1152);
DISPLAY 0.340426 (-6355 1152);
PAINT GREEN (-6355 1152);
DISPLAY INVISIBLE (-6355 1152);
FORCEPROP 1 LAST BODY_TYPE PLUMBING
J 0
(-6445 1107);
DISPLAY 0.340426 (-6445 1107);
PAINT GREEN (-6445 1107);
DISPLAY INVISIBLE (-6445 1107);
FORCEPROP 1 LAST HDL_POWER P12V_STBY
J 0
(-6700 1025);
DISPLAY 0.872340 (-6700 1025);
PAINT ORANGE (-6700 1025);
DISPLAY INVISIBLE (-6700 1025);
FORCEADD GND..1
(-6400 325);
FORCEPROP 3 LASTPIN (-6400 375) SIG_NAME GND\g
J 0
(-6390 385);
DISPLAY 0.659574 (-6390 385);
PAINT MONO (-6390 385);
DISPLAY INVISIBLE (-6390 385);
FORCEPROP 1 LAST VOLTAGE 0.0V
J 0
(-6445 282);
DISPLAY 0.340426 (-6445 282);
PAINT SKYBLUE (-6445 282);
DISPLAY INVISIBLE (-6445 282);
FORCEPROP 2 LAST CDS_LIB mstr_symbols
J 0
(-6400 325);
PAINT MONO (-6400 325);
DISPLAY INVISIBLE (-6400 325);
FORCEPROP 1 LAST SIZE 1B
J 0
(-6325 275);
DISPLAY 0.872340 (-6325 275);
PAINT AQUA (-6325 275);
DISPLAY INVISIBLE (-6325 275);
FORCEPROP 1 LAST PATH I94
J 0
(-6325 325);
DISPLAY 0.872340 (-6325 325);
PAINT AQUA (-6325 325);
DISPLAY INVISIBLE (-6325 325);
FORCEPROP 1 LAST BODY_TYPE PLUMBING
J 0
(-6445 282);
DISPLAY 0.340426 (-6445 282);
PAINT GREEN (-6445 282);
DISPLAY INVISIBLE (-6445 282);
FORCEPROP 1 LAST HDL_POWER GND
J 0
(-6400 475);
DISPLAY 0.872340 (-6400 475);
PAINT GREEN (-6400 475);
DISPLAY INVISIBLE (-6400 475);
FORCEADD GND..1
(-6375 2550);
FORCEPROP 3 LASTPIN (-6375 2600) SIG_NAME GND\g
J 0
(-6365 2610);
DISPLAY 0.659574 (-6365 2610);
PAINT MONO (-6365 2610);
DISPLAY INVISIBLE (-6365 2610);
FORCEPROP 1 LAST VOLTAGE 0.0V
J 0
(-6420 2507);
DISPLAY 0.340426 (-6420 2507);
PAINT SKYBLUE (-6420 2507);
DISPLAY INVISIBLE (-6420 2507);
FORCEPROP 1 LAST SIZE 1B
J 0
(-6300 2500);
DISPLAY 0.872340 (-6300 2500);
PAINT AQUA (-6300 2500);
DISPLAY INVISIBLE (-6300 2500);
FORCEPROP 1 LAST PATH I95
J 0
(-6300 2550);
DISPLAY 0.872340 (-6300 2550);
PAINT AQUA (-6300 2550);
DISPLAY INVISIBLE (-6300 2550);
FORCEPROP 2 LAST CDS_LIB mstr_symbols
J 0
(-6375 2550);
PAINT MONO (-6375 2550);
DISPLAY INVISIBLE (-6375 2550);
FORCEPROP 1 LAST BODY_TYPE PLUMBING
J 0
(-6420 2507);
DISPLAY 0.340426 (-6420 2507);
PAINT GREEN (-6420 2507);
DISPLAY INVISIBLE (-6420 2507);
FORCEPROP 1 LAST HDL_POWER GND
J 0
(-6375 2700);
DISPLAY 0.872340 (-6375 2700);
PAINT GREEN (-6375 2700);
DISPLAY INVISIBLE (-6375 2700);
FORCEADD CAPP..1
(-7275 775);
FORCEPROP 1 LASTPIN (-7275 875) $PN 1
J 0
(-7265 860);
DISPLAY 0.787234 (-7265 860);
PAINT ORANGE (-7265 860);
FORCEPROP 1 LASTPIN (-7275 675) $PN 2
J 0
(-7265 660);
DISPLAY 0.787234 (-7265 660);
PAINT ORANGE (-7265 660);
FORCEPROP 1 LAST PACK_TYPE 3018
J 0
(-7225 625);
DISPLAY 0.617021 (-7225 625);
PAINT SKYBLUE (-7225 625);
FORCEPROP 1 LAST VOLTAGE 16V
J 0
(-7225 725);
DISPLAY 0.617021 (-7225 725);
PAINT SKYBLUE (-7225 725);
FORCEPROP 1 LAST MATERIAL TANT
J 0
(-7225 675);
DISPLAY 0.617021 (-7225 675);
PAINT SKYBLUE (-7225 675);
FORCEPROP 1 LAST PART_NUMBER 724613-112
J 0
(-7225 575);
DISPLAY 0.617021 (-7225 575);
PAINT BLUE (-7225 575);
FORCEPROP 1 LAST TOLERANCE 20%
J 0
(-7225 775);
DISPLAY 0.617021 (-7225 775);
PAINT SKYBLUE (-7225 775);
FORCEPROP 1 LAST VALUE 68UF
J 0
(-7225 825);
DISPLAY 0.617021 (-7225 825);
PAINT SKYBLUE (-7225 825);
FORCEPROP 1 LAST LOCATION C4F5
J 0
(-7225 875);
DISPLAY 0.617021 (-7225 875);
PAINT AQUA (-7225 875);
FORCEPROP 2 LAST SEC_TYPE 3018
J 0
(-7225 975);
DISPLAY 1.021277 (-7225 975);
PAINT ORANGE (-7225 975);
DISPLAY INVISIBLE (-7225 975);
FORCEPROP 2 LAST SEC 1
J 0
(-7225 975);
PAINT MONO (-7225 975);
DISPLAY INVISIBLE (-7225 975);
FORCEPROP 2 LAST CDS_LIB mstr_discrete
J 0
(-7275 775);
PAINT MONO (-7275 775);
DISPLAY INVISIBLE (-7275 775);
FORCEPROP 2 LAST CDS_LOCATION C4F5
J 0
(-7225 875);
DISPLAY 0.617021 (-7225 875);
PAINT AQUA (-7225 875);
DISPLAY INVISIBLE (-7225 875);
FORCEPROP 1 LAST PATH I96
J 0
(-7225 925);
DISPLAY 0.978723 (-7225 925);
PAINT ORANGE (-7225 925);
DISPLAY INVISIBLE (-7225 925);
FORCEADD CAPP..1
(-6900 775);
FORCEPROP 1 LASTPIN (-6900 875) $PN 1
J 0
(-6890 860);
DISPLAY 0.787234 (-6890 860);
PAINT ORANGE (-6890 860);
FORCEPROP 1 LASTPIN (-6900 675) $PN 2
J 0
(-6890 660);
DISPLAY 0.787234 (-6890 660);
PAINT ORANGE (-6890 660);
FORCEPROP 1 LAST PACK_TYPE 3018
J 0
(-6850 625);
DISPLAY 0.617021 (-6850 625);
PAINT SKYBLUE (-6850 625);
FORCEPROP 1 LAST VOLTAGE 16V
J 0
(-6850 725);
DISPLAY 0.617021 (-6850 725);
PAINT SKYBLUE (-6850 725);
FORCEPROP 1 LAST MATERIAL TANT
J 0
(-6850 675);
DISPLAY 0.617021 (-6850 675);
PAINT SKYBLUE (-6850 675);
FORCEPROP 1 LAST VALUE 68UF
J 0
(-6850 825);
DISPLAY 0.617021 (-6850 825);
PAINT SKYBLUE (-6850 825);
FORCEPROP 1 LAST LOCATION C4B14
J 0
(-6850 875);
DISPLAY 0.617021 (-6850 875);
PAINT AQUA (-6850 875);
FORCEPROP 1 LAST TOLERANCE 20%
J 0
(-6850 775);
DISPLAY 0.617021 (-6850 775);
PAINT SKYBLUE (-6850 775);
FORCEPROP 1 LAST PART_NUMBER 724613-112
J 0
(-6850 575);
DISPLAY 0.617021 (-6850 575);
PAINT BLUE (-6850 575);
FORCEPROP 2 LAST SEC_TYPE 3018
J 0
(-6850 975);
DISPLAY 1.021277 (-6850 975);
PAINT ORANGE (-6850 975);
DISPLAY INVISIBLE (-6850 975);
FORCEPROP 2 LAST SEC 1
J 0
(-6850 975);
PAINT MONO (-6850 975);
DISPLAY INVISIBLE (-6850 975);
FORCEPROP 2 LAST CDS_LIB mstr_discrete
J 0
(-6900 775);
PAINT MONO (-6900 775);
DISPLAY INVISIBLE (-6900 775);
FORCEPROP 2 LAST CDS_LOCATION C4B14
J 0
(-6850 875);
DISPLAY 0.617021 (-6850 875);
PAINT AQUA (-6850 875);
DISPLAY INVISIBLE (-6850 875);
FORCEPROP 1 LAST PATH I97
J 0
(-6850 925);
DISPLAY 0.978723 (-6850 925);
PAINT ORANGE (-6850 925);
DISPLAY INVISIBLE (-6850 925);
FORCEADD CAPP..1
(-5300 750);
FORCEPROP 1 LAST VOLTAGE 16V
J 0
(-5250 700);
DISPLAY 0.617021 (-5250 700);
PAINT SKYBLUE (-5250 700);
FORCEPROP 1 LASTPIN (-5300 850) $PN 1
J 0
(-5290 835);
DISPLAY 0.787234 (-5290 835);
PAINT ORANGE (-5290 835);
FORCEPROP 1 LASTPIN (-5300 650) $PN 2
J 0
(-5290 635);
DISPLAY 0.787234 (-5290 635);
PAINT ORANGE (-5290 635);
FORCEPROP 1 LAST PACK_TYPE 3018
J 0
(-5250 600);
DISPLAY 0.617021 (-5250 600);
PAINT SKYBLUE (-5250 600);
FORCEPROP 1 LAST TOLERANCE 20%
J 0
(-5250 750);
DISPLAY 0.617021 (-5250 750);
PAINT SKYBLUE (-5250 750);
FORCEPROP 1 LAST MATERIAL TANT
J 0
(-5250 650);
DISPLAY 0.617021 (-5250 650);
PAINT SKYBLUE (-5250 650);
FORCEPROP 1 LAST PART_NUMBER 724613-112
J 0
(-5250 550);
DISPLAY 0.617021 (-5250 550);
PAINT BLUE (-5250 550);
FORCEPROP 1 LAST VALUE 68UF
J 0
(-5250 800);
DISPLAY 0.617021 (-5250 800);
PAINT SKYBLUE (-5250 800);
FORCEPROP 1 LAST LOCATION C3T6
J 0
(-5250 850);
DISPLAY 0.617021 (-5250 850);
PAINT AQUA (-5250 850);
FORCEPROP 2 LAST SEC_TYPE 3018
J 0
(-5250 950);
DISPLAY 1.021277 (-5250 950);
PAINT ORANGE (-5250 950);
DISPLAY INVISIBLE (-5250 950);
FORCEPROP 2 LAST SEC 1
J 0
(-5250 950);
PAINT MONO (-5250 950);
DISPLAY INVISIBLE (-5250 950);
FORCEPROP 2 LAST CDS_LIB mstr_discrete
J 0
(-5300 750);
PAINT MONO (-5300 750);
DISPLAY INVISIBLE (-5300 750);
FORCEPROP 1 LAST PATH I98
J 0
(-5250 900);
DISPLAY 0.978723 (-5250 900);
PAINT ORANGE (-5250 900);
DISPLAY INVISIBLE (-5250 900);
FORCEPROP 2 LAST CDS_LOCATION C3T6
J 0
(-5250 850);
DISPLAY 0.617021 (-5250 850);
PAINT AQUA (-5250 850);
DISPLAY INVISIBLE (-5250 850);
FORCEADD CAPP..1
(-5750 775);
FORCEPROP 1 LAST MATERIAL TANT
J 0
(-5700 675);
DISPLAY 0.617021 (-5700 675);
PAINT SKYBLUE (-5700 675);
FORCEPROP 1 LASTPIN (-5750 875) $PN 1
J 0
(-5740 860);
DISPLAY 0.787234 (-5740 860);
PAINT ORANGE (-5740 860);
FORCEPROP 1 LASTPIN (-5750 675) $PN 2
J 0
(-5740 660);
DISPLAY 0.787234 (-5740 660);
PAINT ORANGE (-5740 660);
FORCEPROP 1 LAST PACK_TYPE 3018
J 0
(-5700 625);
DISPLAY 0.617021 (-5700 625);
PAINT SKYBLUE (-5700 625);
FORCEPROP 1 LAST PART_NUMBER 724613-112
J 0
(-5700 575);
DISPLAY 0.617021 (-5700 575);
PAINT BLUE (-5700 575);
FORCEPROP 1 LAST VOLTAGE 16V
J 0
(-5700 725);
DISPLAY 0.617021 (-5700 725);
PAINT SKYBLUE (-5700 725);
FORCEPROP 1 LAST TOLERANCE 20%
J 0
(-5700 775);
DISPLAY 0.617021 (-5700 775);
PAINT SKYBLUE (-5700 775);
FORCEPROP 1 LAST VALUE 68UF
J 0
(-5700 825);
DISPLAY 0.617021 (-5700 825);
PAINT SKYBLUE (-5700 825);
FORCEPROP 1 LAST LOCATION C9M3
J 0
(-5700 875);
DISPLAY 0.617021 (-5700 875);
PAINT AQUA (-5700 875);
FORCEPROP 2 LAST SEC_TYPE 3018
J 0
(-5700 975);
DISPLAY 1.021277 (-5700 975);
PAINT ORANGE (-5700 975);
DISPLAY INVISIBLE (-5700 975);
FORCEPROP 2 LAST SEC 1
J 0
(-5700 975);
PAINT MONO (-5700 975);
DISPLAY INVISIBLE (-5700 975);
FORCEPROP 2 LAST CDS_LIB mstr_discrete
J 0
(-5750 775);
PAINT MONO (-5750 775);
DISPLAY INVISIBLE (-5750 775);
FORCEPROP 2 LAST CDS_LOCATION C9M3
J 0
(-5700 875);
DISPLAY 0.617021 (-5700 875);
PAINT AQUA (-5700 875);
DISPLAY INVISIBLE (-5700 875);
FORCEPROP 1 LAST PATH I99
J 0
(-5700 925);
DISPLAY 0.978723 (-5700 925);
PAINT ORANGE (-5700 925);
DISPLAY INVISIBLE (-5700 925);
FORCEADD DNS..2
(-5520 4720);
PAINT RED (-5520 4720);
FORCEPROP 2 LAST CDS_LIB mstr_misc
J 0
(-5520 4720);
PAINT ORANGE (-5520 4720);
DISPLAY INVISIBLE (-5520 4720);
FORCEPROP 1 LAST COMMENT_BODY TRUE
R 1
J 0
(-5445 4495);
DISPLAY 0.872340 (-5445 4495);
PAINT GREEN (-5445 4495);
DISPLAY INVISIBLE (-5445 4495);
FORCEADD DNS..2
(-6470 4720);
PAINT RED (-6470 4720);
FORCEPROP 2 LAST CDS_LIB mstr_misc
J 0
(-6470 4720);
PAINT ORANGE (-6470 4720);
DISPLAY INVISIBLE (-6470 4720);
FORCEPROP 1 LAST COMMENT_BODY TRUE
R 1
J 0
(-6395 4495);
DISPLAY 0.872340 (-6395 4495);
PAINT GREEN (-6395 4495);
DISPLAY INVISIBLE (-6395 4495);
FORCEADD DNS..2
(-5520 4145);
PAINT RED (-5520 4145);
FORCEPROP 2 LAST CDS_LIB mstr_misc
J 0
(-5520 4145);
PAINT ORANGE (-5520 4145);
DISPLAY INVISIBLE (-5520 4145);
FORCEPROP 1 LAST COMMENT_BODY TRUE
R 1
J 0
(-5445 3920);
DISPLAY 0.872340 (-5445 3920);
PAINT GREEN (-5445 3920);
DISPLAY INVISIBLE (-5445 3920);
FORCEADD DNS..2
(-3370 3645);
PAINT RED (-3370 3645);
FORCEPROP 2 LAST CDS_LIB mstr_misc
J 0
(-3370 3645);
PAINT MONO (-3370 3645);
DISPLAY INVISIBLE (-3370 3645);
FORCEPROP 1 LAST COMMENT_BODY TRUE
R 1
J 0
(-3295 3420);
DISPLAY 0.872340 (-3295 3420);
PAINT GREEN (-3295 3420);
DISPLAY INVISIBLE (-3295 3420);
FORCEADD DNS..2
(-1620 3645);
PAINT RED (-1620 3645);
FORCEPROP 2 LAST CDS_LIB mstr_misc
J 0
(-1620 3645);
PAINT ORANGE (-1620 3645);
DISPLAY INVISIBLE (-1620 3645);
FORCEPROP 1 LAST COMMENT_BODY TRUE
R 1
J 0
(-1545 3420);
DISPLAY 0.872340 (-1545 3420);
PAINT GREEN (-1545 3420);
DISPLAY INVISIBLE (-1545 3420);
FORCEADD DNS..2
(-7345 4120);
PAINT RED (-7345 4120);
FORCEPROP 2 LAST CDS_LIB mstr_misc
J 0
(-7345 4120);
PAINT ORANGE (-7345 4120);
DISPLAY INVISIBLE (-7345 4120);
FORCEPROP 1 LAST COMMENT_BODY TRUE
R 1
J 0
(-7270 3895);
DISPLAY 0.872340 (-7270 3895);
PAINT GREEN (-7270 3895);
DISPLAY INVISIBLE (-7270 3895);
FORCEADD DNS..2
(-6420 4120);
PAINT RED (-6420 4120);
FORCEPROP 2 LAST CDS_LIB mstr_misc
J 0
(-6420 4120);
PAINT ORANGE (-6420 4120);
DISPLAY INVISIBLE (-6420 4120);
FORCEPROP 1 LAST COMMENT_BODY TRUE
R 1
J 0
(-6345 3895);
DISPLAY 0.872340 (-6345 3895);
PAINT GREEN (-6345 3895);
DISPLAY INVISIBLE (-6345 3895);
FORCEADD DNS..2
(-2670 3645);
PAINT RED (-2670 3645);
FORCEPROP 2 LAST CDS_LIB mstr_misc
J 0
(-2670 3645);
PAINT MONO (-2670 3645);
DISPLAY INVISIBLE (-2670 3645);
FORCEPROP 1 LAST COMMENT_BODY TRUE
R 1
J 0
(-2595 3420);
DISPLAY 0.872340 (-2595 3420);
PAINT GREEN (-2595 3420);
DISPLAY INVISIBLE (-2595 3420);
FORCEADD DNS..2
(-4595 4145);
PAINT RED (-4595 4145);
FORCEPROP 2 LAST CDS_LIB mstr_misc
J 0
(-4595 4145);
PAINT ORANGE (-4595 4145);
DISPLAY INVISIBLE (-4595 4145);
FORCEPROP 1 LAST COMMENT_BODY TRUE
R 1
J 0
(-4520 3920);
DISPLAY 0.872340 (-4520 3920);
PAINT GREEN (-4520 3920);
DISPLAY INVISIBLE (-4520 3920);
FORCEADD DNS..2
(-1945 3645);
PAINT RED (-1945 3645);
FORCEPROP 2 LAST CDS_LIB mstr_misc
J 0
(-1945 3645);
PAINT MONO (-1945 3645);
DISPLAY INVISIBLE (-1945 3645);
FORCEPROP 1 LAST COMMENT_BODY TRUE
R 1
J 0
(-1870 3420);
DISPLAY 0.872340 (-1870 3420);
PAINT GREEN (-1870 3420);
DISPLAY INVISIBLE (-1870 3420);
FORCEADD DNS..2
(-4595 4720);
PAINT RED (-4595 4720);
FORCEPROP 2 LAST CDS_LIB mstr_misc
J 0
(-4595 4720);
PAINT ORANGE (-4595 4720);
DISPLAY INVISIBLE (-4595 4720);
FORCEPROP 1 LAST COMMENT_BODY TRUE
R 1
J 0
(-4520 4495);
DISPLAY 0.872340 (-4520 4495);
PAINT GREEN (-4520 4495);
DISPLAY INVISIBLE (-4520 4495);
FORCEADD DNS..2
(-2295 3645);
PAINT RED (-2295 3645);
FORCEPROP 2 LAST CDS_LIB mstr_misc
J 0
(-2295 3645);
PAINT MONO (-2295 3645);
DISPLAY INVISIBLE (-2295 3645);
FORCEPROP 1 LAST COMMENT_BODY TRUE
R 1
J 0
(-2220 3420);
DISPLAY 0.872340 (-2220 3420);
PAINT GREEN (-2220 3420);
DISPLAY INVISIBLE (-2220 3420);
FORCEADD INTEL_CORP_BPAGE..1
(100 100);
FORCEPROP 1 LAST CDS_CON_LAST_MODIFIED Fri Jun 16 17:49:11 2017
J 0
(-1325 425);
DISPLAY 1.361702 (-1325 425);
PAINT GREEN (-1325 425);
DISPLAY INVISIBLE (-1325 425);
FORCEPROP 1 LAST CUSTOM_TXT_CDS <CURRENT_DESIGN_SHEET> OF <TOTAL_DESIGN_SHEETS>
J 0
(-400 125);
PAINT ORANGE (-400 125);
FORCEPROP 1 LAST CUSTOM_TXT_CDS <CON_LAST_MODIFIED>
J 0
(-3900 200);
PAINT ORANGE (-3900 200);
FORCEPROP 2 LAST CUSTOM_TXT_CDS <XR_PAGE_TITLE>
J 0
(-7790 5350);
DISPLAY 0.638298 (-7790 5350);
PAINT PINK (-7790 5350);
DISPLAY INVISIBLE (-7790 5350);
FORCEPROP 1 LAST SCH_TITLE MOUNTING HOLES + POWER INPUT CONNECTOR
J 0
(-7850 150);
DISPLAY 1.212766 (-7850 150);
PAINT ORANGE (-7850 150);
FORCEPROP 2 LAST PAGE_BORDER TRUE
J 0
(-7790 5350);
DISPLAY 0.851064 (-7790 5350);
PAINT PINK (-7790 5350);
DISPLAY INVISIBLE (-7790 5350);
FORCEPROP 2 LAST CDS_LIB mstr_symbols
J 0
(100 100);
DISPLAY 1.361702 (100 100);
PAINT ORANGE (100 100);
DISPLAY INVISIBLE (100 100);
FORCEPROP 1 LAST COMMENT_BODY TRUE
J 0
(112 112);
DISPLAY 0.617021 (112 112);
PAINT GREEN (112 112);
DISPLAY INVISIBLE (112 112);
FORCEPROP 2 LAST CDS_XR_PAGE_TITLE CR-195 : @BASEBOARD_FAB2_LIB.BASEBOARD_FAB2(SCH_1):PAGE195
J 0
(-7790 5350);
DISPLAY 0.638298 (-7790 5350);
PAINT PINK (-7790 5350);
DISPLAY INVISIBLE (-7790 5350);
FORCEADD DNS..2
(-3020 3645);
PAINT RED (-3020 3645);
FORCEPROP 2 LAST CDS_LIB mstr_misc
J 0
(-3020 3645);
PAINT MONO (-3020 3645);
DISPLAY INVISIBLE (-3020 3645);
FORCEPROP 1 LAST COMMENT_BODY TRUE
R 1
J 0
(-2945 3420);
DISPLAY 0.872340 (-2945 3420);
PAINT GREEN (-2945 3420);
DISPLAY INVISIBLE (-2945 3420);
FORCEADD DNS..2
(-3695 3645);
PAINT RED (-3695 3645);
FORCEPROP 2 LAST CDS_LIB mstr_misc
J 0
(-3695 3645);
PAINT MONO (-3695 3645);
DISPLAY INVISIBLE (-3695 3645);
FORCEPROP 1 LAST COMMENT_BODY TRUE
R 1
J 0
(-3620 3420);
DISPLAY 0.872340 (-3620 3420);
PAINT GREEN (-3620 3420);
DISPLAY INVISIBLE (-3620 3420);
WIRE 16 -1 (-6375 2225)(-6375 2275);
WIRE 16 -1 (-6150 2225)(-6375 2225);
WIRE 16 -1 (-6525 2225)(-6375 2225);
WIRE 16 -1 (-6525 2225)(-6875 2225);
WIRE 16 -1 (-6525 2050)(-6525 2225);
WIRE 16 -1 (-5725 2225)(-6150 2225);
WIRE 16 -1 (-6150 2050)(-6150 2225);
WIRE 16 -1 (-5275 2225)(-5725 2225);
WIRE 16 -1 (-5725 2050)(-5725 2225);
WIRE 16 -1 (-6875 2225)(-7250 2225);
WIRE 16 -1 (-6875 2050)(-6875 2225);
WIRE 16 -1 (-7675 2225)(-7250 2225);
WIRE 16 -1 (-7250 2050)(-7250 2225);
WIRE 16 -1 (-4850 2225)(-5275 2225);
WIRE 16 -1 (-5275 2225)(-5275 2025);
WIRE 16 -1 (-4850 2050)(-4850 2225);
WIRE 16 -1 (-7675 2225)(-7675 2050);
WIRE 16 -1 (-6375 1650)(-6375 1550);
WIRE 16 -1 (-6150 1650)(-6375 1650);
WIRE 16 -1 (-6525 1650)(-6375 1650);
WIRE 16 -1 (-6525 1650)(-6875 1650);
WIRE 16 -1 (-6525 1850)(-6525 1650);
WIRE 16 -1 (-5725 1650)(-6150 1650);
WIRE 16 -1 (-6150 1850)(-6150 1650);
WIRE 16 -1 (-5275 1650)(-5725 1650);
WIRE 16 -1 (-5725 1850)(-5725 1650);
WIRE 16 -1 (-6875 1650)(-7250 1650);
WIRE 16 -1 (-6875 1850)(-6875 1650);
WIRE 16 -1 (-7675 1650)(-7250 1650);
WIRE 16 -1 (-7250 1850)(-7250 1650);
WIRE 16 -1 (-4850 1650)(-5275 1650);
WIRE 16 -1 (-5275 1825)(-5275 1650);
WIRE 16 -1 (-4850 1850)(-4850 1650);
WIRE 16 -1 (-7675 1850)(-7675 1650);
WIRE 16 -1 (-7350 4750)(-7350 4700);
WIRE 16 -1 (-7400 4750)(-7350 4750);
WIRE 16 -1 (-3700 2350)(-3700 2700);
WIRE 16 -1 (-3700 2300)(-3700 2350);
WIRE 16 -1 (-3700 2350)(-3350 2350);
WIRE 16 -1 (-3700 2250)(-3700 2300);
WIRE 16 -1 (-3350 2300)(-3700 2300);
WIRE 16 -1 (-3350 2250)(-3700 2250);
WIRE 16 -1 (-475 3575)(-475 3425);
WIRE 16 -1 (-475 3675)(-475 3575);
WIRE 16 -1 (-725 3575)(-475 3575);
WIRE 16 -1 (-475 3775)(-475 3675);
WIRE 16 -1 (-725 3675)(-475 3675);
WIRE 16 -1 (-725 3775)(-475 3775);
WIRE 16 -1 (-3550 1950)(-3550 2050);
WIRE 16 -1 (-3550 2050)(-3550 2100);
WIRE 16 -1 (-3350 2050)(-3550 2050);
WIRE 16 -1 (-3550 2100)(-3550 2150);
WIRE 16 -1 (-3350 2100)(-3550 2100);
WIRE 16 -1 (-3350 2150)(-3550 2150);
WIRE 16 -1 (-3700 3275)(-3700 3350);
WIRE 16 -1 (-3700 3350)(-3375 3350);
WIRE 16 -1 (-3700 3550)(-3700 3350);
WIRE 16 -1 (-3375 3350)(-3025 3350);
WIRE 16 -1 (-3375 3350)(-3375 3550);
WIRE 16 -1 (-2675 3350)(-3025 3350);
WIRE 16 -1 (-3025 3550)(-3025 3350);
WIRE 16 -1 (-2300 3350)(-2675 3350);
WIRE 16 -1 (-2675 3550)(-2675 3350);
WIRE 16 -1 (-1950 3350)(-2300 3350);
WIRE 16 -1 (-2300 3550)(-2300 3350);
WIRE 16 -1 (-1625 3350)(-1950 3350);
WIRE 16 -1 (-1950 3550)(-1950 3350);
WIRE 16 -1 (-1625 3550)(-1625 3350);
WIRE 16 -1 (-2500 1950)(-2500 2050);
WIRE 16 -1 (-2500 2050)(-2500 2100);
WIRE 16 -1 (-2500 2050)(-2700 2050);
WIRE 16 -1 (-2500 2150)(-2500 2100);
WIRE 16 -1 (-2700 2100)(-2500 2100);
WIRE 16 -1 (-2700 2150)(-2500 2150);
WIRE 16 -1 (-2350 2700)(-2350 2350);
WIRE 16 -1 (-2350 2300)(-2350 2350);
WIRE 16 -1 (-2700 2350)(-2350 2350);
WIRE 16 -1 (-2350 2250)(-2350 2300);
WIRE 16 -1 (-2350 2300)(-2700 2300);
WIRE 16 -1 (-2700 2250)(-2350 2250);
WIRE 16 -1 (-1625 3825)(-1625 3975);
WIRE 16 -1 (-1625 3825)(-1950 3825);
WIRE 16 -1 (-1625 3750)(-1625 3825);
WIRE 16 -1 (-1950 3825)(-2300 3825);
WIRE 16 -1 (-1950 3750)(-1950 3825);
WIRE 16 -1 (-2300 3825)(-2675 3825);
WIRE 16 -1 (-2300 3750)(-2300 3825);
WIRE 16 -1 (-3025 3825)(-2675 3825);
WIRE 16 -1 (-2675 3825)(-2675 3750);
WIRE 16 -1 (-3375 3825)(-3025 3825);
WIRE 16 -1 (-3025 3825)(-3025 3750);
WIRE 16 -1 (-3700 3825)(-3375 3825);
WIRE 16 -1 (-3375 3825)(-3375 3750);
WIRE 16 -1 (-3700 3750)(-3700 3825);
WIRE 16 -1 (-6900 4725)(-6900 4575);
WIRE 16 -1 (-6725 4725)(-6900 4725);
WIRE 16 -1 (-6850 4125)(-6850 3975);
WIRE 16 -1 (-6675 4125)(-6850 4125);
WIRE 16 -1 (-5025 4725)(-5025 4575);
WIRE 16 -1 (-4850 4725)(-5025 4725);
WIRE 16 -1 (-5950 4725)(-5950 4575);
WIRE 16 -1 (-5775 4725)(-5950 4725);
WIRE 16 -1 (-7775 4125)(-7775 3975);
WIRE 16 -1 (-7600 4125)(-7775 4125);
WIRE 16 -1 (-5950 4150)(-5950 4000);
WIRE 16 -1 (-5775 4150)(-5950 4150);
WIRE 16 -1 (-5025 4150)(-5025 4000);
WIRE 16 -1 (-4850 4150)(-5025 4150);
WIRE 16 -1 (-550 2350)(-550 2700);
WIRE 16 -1 (-550 2300)(-550 2350);
WIRE 16 -1 (-925 2350)(-550 2350);
WIRE 16 -1 (-550 2250)(-550 2300);
WIRE 16 -1 (-925 2300)(-550 2300);
WIRE 16 -1 (-925 2250)(-550 2250);
WIRE 16 -1 (-650 2050)(-650 1950);
WIRE 16 -1 (-650 2100)(-650 2050);
WIRE 16 -1 (-650 2050)(-925 2050);
WIRE 16 -1 (-650 2150)(-650 2100);
WIRE 16 -1 (-650 2100)(-925 2100);
WIRE 16 -1 (-925 2150)(-650 2150);
WIRE 16 -1 (-1900 2350)(-1900 2700);
WIRE 16 -1 (-1900 2350)(-1900 2300);
WIRE 16 -1 (-1575 2350)(-1900 2350);
WIRE 16 -1 (-1900 2300)(-1900 2250);
WIRE 16 -1 (-1900 2300)(-1575 2300);
WIRE 16 -1 (-1900 2250)(-1575 2250);
WIRE 16 -1 (-1850 2050)(-1850 1950);
WIRE 16 -1 (-1850 2100)(-1850 2050);
WIRE 16 -1 (-1850 2050)(-1575 2050);
WIRE 16 -1 (-1850 2150)(-1850 2100);
WIRE 16 -1 (-1850 2100)(-1575 2100);
WIRE 16 -1 (-1575 2150)(-1850 2150);
WIRE 16 -1 (-6250 3200)(-6250 3325);
WIRE 16 -1 (-6150 3200)(-6250 3200);
WIRE 16 -1 (-6675 3200)(-6250 3200);
WIRE 16 -1 (-7175 3200)(-6675 3200);
WIRE 16 -1 (-6675 3050)(-6675 3200);
WIRE 16 -1 (-5650 3200)(-6150 3200);
WIRE 16 -1 (-6150 3025)(-6150 3200);
WIRE 16 -1 (-5650 3000)(-5650 3200);
WIRE 16 -1 (-7175 3050)(-7175 3200);
WIRE 16 -1 (-6400 1050)(-6400 1100);
WIRE 16 -1 (-6175 1050)(-6400 1050);
WIRE 16 -1 (-6550 1050)(-6400 1050);
WIRE 16 -1 (-6550 1050)(-6900 1050);
WIRE 16 -1 (-6550 875)(-6550 1050);
WIRE 16 -1 (-5750 1050)(-6175 1050);
WIRE 16 -1 (-6175 875)(-6175 1050);
WIRE 16 -1 (-5300 1050)(-5750 1050);
WIRE 16 -1 (-5750 875)(-5750 1050);
WIRE 16 -1 (-6900 1050)(-7275 1050);
WIRE 16 -1 (-6900 875)(-6900 1050);
WIRE 16 -1 (-7700 1050)(-7275 1050);
WIRE 16 -1 (-7275 875)(-7275 1050);
WIRE 16 -1 (-4875 1050)(-5300 1050);
WIRE 16 -1 (-5300 1050)(-5300 850);
WIRE 16 -1 (-4875 875)(-4875 1050);
WIRE 16 -1 (-7700 1050)(-7700 875);
WIRE 16 -1 (-6400 475)(-6400 375);
WIRE 16 -1 (-6175 475)(-6400 475);
WIRE 16 -1 (-6550 475)(-6400 475);
WIRE 16 -1 (-6550 475)(-6900 475);
WIRE 16 -1 (-6550 675)(-6550 475);
WIRE 16 -1 (-5750 475)(-6175 475);
WIRE 16 -1 (-6175 675)(-6175 475);
WIRE 16 -1 (-5300 475)(-5750 475);
WIRE 16 -1 (-5750 675)(-5750 475);
WIRE 16 -1 (-6900 475)(-7275 475);
WIRE 16 -1 (-6900 675)(-6900 475);
WIRE 16 -1 (-7700 475)(-7275 475);
WIRE 16 -1 (-7275 675)(-7275 475);
WIRE 16 -1 (-4875 475)(-5300 475);
WIRE 16 -1 (-5300 650)(-5300 475);
WIRE 16 -1 (-4875 675)(-4875 475);
WIRE 16 -1 (-7700 675)(-7700 475);
WIRE 16 -1 (-6375 2625)(-6375 2600);
WIRE 16 -1 (-6375 2625)(-6150 2625);
WIRE 16 -1 (-6675 2625)(-6375 2625);
WIRE 16 -1 (-7175 2625)(-6675 2625);
WIRE 16 -1 (-6675 2850)(-6675 2625);
WIRE 16 -1 (-5650 2625)(-6150 2625);
WIRE 16 -1 (-6150 2825)(-6150 2625);
WIRE 16 -1 (-5650 2800)(-5650 2625);
WIRE 16 -1 (-7175 2850)(-7175 2625);
WIRE 3 682 (-7800 4950)(-7800 4500);
WIRE 3 682 (-7200 4950)(-7800 4950);
WIRE 3 682 (-7800 4500)(-7200 4500);
WIRE 3 682 (-7200 4500)(-7200 4950);
WIRE 16 -1 (-4225 550)(-4200 550);
WIRE 16 682 (-4225 4975)(-4225 550);
WIRE 3 682 (-3850 3300)(-1350 3300);
WIRE 3 682 (-1350 3300)(-1350 3875);
WIRE 3 682 (-3850 3300)(-3850 3875);
WIRE 3 682 (-3850 3875)(-1350 3875);
WIRE 3 2175 (-1750 1750)(-750 1750);
WIRE 3 2175 (-750 2625)(-750 1750);
WIRE 3 2175 (-1750 2625)(-1750 1750);
WIRE 3 2175 (-1750 2625)(-750 2625);
WIRE 3 682 (-2400 1750)(-3650 1750);
WIRE 3 682 (-2400 2550)(-2400 1750);
WIRE 3 682 (-3650 1750)(-3650 2550);
WIRE 3 682 (-3650 2550)(-2400 2550);
DOT 1 (-550 2350);
DOT 1 (-3700 2350);
DOT 1 (-1900 2350);
DOT 1 (-1900 2300);
DOT 1 (-2500 2100);
DOT 1 (-2500 2050);
DOT 1 (-3550 2050);
DOT 1 (-3550 2100);
DOT 1 (-3700 2300);
DOT 1 (-2350 2300);
DOT 1 (-2350 2350);
DOT 1 (-1850 2050);
DOT 1 (-6900 475);
DOT 1 (-6175 475);
DOT 1 (-6150 1650);
DOT 1 (-6875 1650);
DOT 1 (-475 3675);
DOT 1 (-475 3575);
DOT 1 (-2300 3825);
DOT 1 (-2675 3825);
DOT 1 (-3025 3825);
DOT 1 (-3375 3825);
DOT 1 (-5275 2225);
DOT 1 (-5725 2225);
DOT 1 (-5275 1650);
DOT 1 (-5300 1050);
DOT 1 (-5725 1650);
DOT 1 (-5750 1050);
DOT 1 (-5300 475);
DOT 1 (-5750 475);
DOT 1 (-6150 3200);
DOT 1 (-6250 3200);
DOT 1 (-6675 3200);
DOT 1 (-6150 2625);
DOT 1 (-6375 2625);
DOT 1 (-6150 2225);
DOT 1 (-6375 2225);
DOT 1 (-6525 2225);
DOT 1 (-6675 2625);
DOT 1 (-6875 2225);
DOT 1 (-7250 2225);
DOT 1 (-6375 1650);
DOT 1 (-6525 1650);
DOT 1 (-6175 1050);
DOT 1 (-6550 1050);
DOT 1 (-6400 1050);
DOT 1 (-6900 1050);
DOT 1 (-6400 475);
DOT 1 (-6550 475);
DOT 1 (-7250 1650);
DOT 1 (-7275 1050);
DOT 1 (-7275 475);
DOT 1 (-550 2300);
DOT 1 (-1850 2100);
DOT 1 (-650 2100);
DOT 1 (-650 2050);
DOT 1 (-1950 3350);
DOT 1 (-2300 3350);
DOT 1 (-3025 3350);
DOT 1 (-1950 3825);
DOT 1 (-1625 3825);
DOT 1 (-3375 3350);
DOT 1 (-3700 3350);
DOT 1 (-2675 3350);
FORCENOTE
BULK CAPS TO SUPPORT FAST PROCHOT
(-7175 3525) 0;
DISPLAY LEFT (-7175 3525);
DISPLAY 1.595745 (-7175 3525);
PAINT PURPLE (-7175 3525);
FORCENOTE
TP FAB1 CHANGE SYMBOL 0302
(-3650 1425) 0;
DISPLAY LEFT (-3650 1425);
DISPLAY 1.021277 (-3650 1425);
PAINT RED (-3650 1425);
FORCENOTE
ROOM: HOT_SWAP
(-3520 1575) 0;
DISPLAY LEFT (-3520 1575);
DISPLAY 1.021277 (-3520 1575);
PAINT PURPLE (-3520 1575);
FORCENOTE
BOM_COST=TEST_MFG
(-6625 3700) 0;
DISPLAY LEFT (-6625 3700);
DISPLAY 1.021277 (-6625 3700);
PAINT PURPLE (-6625 3700);
FORCENOTE
POP J1E1 (AIR MAX CONNECTOR) 1218
(-3650 1500) 0;
DISPLAY LEFT (-3650 1500);
DISPLAY 1.021277 (-3650 1500);
PAINT RED (-3650 1500);
FORCENOTE
GUIDE PIN
(-1200 3325) 0;
DISPLAY LEFT (-1200 3325);
DISPLAY 1.595745 (-1200 3325);
PAINT PURPLE (-1200 3325);
FORCENOTE
ROOM=MOUNTING_HOLES
(-6625 3775) 0;
DISPLAY LEFT (-6625 3775);
DISPLAY 1.021277 (-6625 3775);
PAINT PURPLE (-6625 3775);
FORCENOTE
NOPOP J1D1 (PRESSFIT CABLE) 1218
(-1750 1450) 0;
DISPLAY LEFT (-1750 1450);
DISPLAY 1.021277 (-1750 1450);
PAINT RED (-1750 1450);
FORCENOTE
ROOM: HOT_SWAP
(-1620 1525) 0;
DISPLAY LEFT (-1620 1525);
DISPLAY 1.021277 (-1620 1525);
PAINT PURPLE (-1620 1525);
FORCENOTE
POWER CONN: 40A MAX
(-1650 1625) 0;
DISPLAY LEFT (-1650 1625);
DISPLAY 1.595745 (-1650 1625);
PAINT PURPLE (-1650 1625);
FORCENOTE
TP FAB1 NOPOP CAPS 0412
(-3575 3225) 0;
DISPLAY LEFT (-3575 3225);
DISPLAY 1.021277 (-3575 3225);
PAINT RED (-3575 3225);
FORCENOTE
POWER CONN: 40AMAX
(-3550 1650) 0;
DISPLAY LEFT (-3550 1650);
DISPLAY 1.595745 (-3550 1650);
PAINT PURPLE (-3550 1650);
FORCENOTE
TP FAB1 CHANGE SYMBOL 0316
(-7800 4425) 0;
DISPLAY LEFT (-7800 4425);
DISPLAY 1.021277 (-7800 4425);
PAINT RED (-7800 4425);
QUIT
